(kicad_sch
	(version 20250114)
	(generator "eeschema")
	(generator_version "9.0")
	(paper "A3")
	(title_block
		(title "Kintex 410T devboard")
		(date "2024-04-03")
		(rev "1.1.2")
	)
	(text "MODE2"
		(exclude_from_sim no)
		(at 68.58 252.095 0)
		(effects
			(font
				(size 1.27 1.27)
			)
			(justify left bottom)
		)
	)
	(text "Pull up"
		(exclude_from_sim no)
		(at 25.4 52.705 0)
		(effects
			(font
				(size 1.27 1.27)
			)
			(justify left bottom)
		)
	)
	(text "LED_MODE"
		(exclude_from_sim no)
		(at 68.58 114.935 0)
		(effects
			(font
				(size 1.27 1.27)
			)
			(justify left bottom)
		)
	)
	(text "Pull up"
		(exclude_from_sim no)
		(at 25.4 224.155 0)
		(effects
			(font
				(size 1.27 1.27)
			)
			(justify left bottom)
		)
	)
	(text "PHYAD0"
		(exclude_from_sim no)
		(at 68.58 106.045 0)
		(effects
			(font
				(size 1.27 1.27)
			)
			(justify left bottom)
		)
	)
	(text "MODE0\n"
		(exclude_from_sim no)
		(at 68.58 257.175 0)
		(effects
			(font
				(size 1.27 1.27)
			)
			(justify left bottom)
		)
	)
	(text "default:\nMODE[2:0] : 111 (see datasheet table 3-4)\nPHYAD[0]: 0\nREGOFF: 0, INT 1.2 V Reg enabled\n~{INTSEL}: 0, REF_CLK Out mode"
		(exclude_from_sim no)
		(at 19.685 280.035 0)
		(effects
			(font
				(size 1.27 1.27)
			)
			(justify left bottom)
		)
	)
	(text "MODE1"
		(exclude_from_sim no)
		(at 68.58 254.635 0)
		(effects
			(font
				(size 1.27 1.27)
			)
			(justify left bottom)
		)
	)
	(text "MODE3"
		(exclude_from_sim no)
		(at 68.58 55.88 0)
		(effects
			(font
				(size 1.27 1.27)
			)
			(justify left bottom)
		)
	)
	(text "PHYAD0"
		(exclude_from_sim no)
		(at 68.58 72.39 0)
		(effects
			(font
				(size 1.27 1.27)
			)
			(justify left bottom)
		)
	)
	(text "NOTE:\nPlace close to PHY IC"
		(exclude_from_sim no)
		(at 97.155 211.455 0)
		(effects
			(font
				(size 1.27 1.27)
			)
			(justify left bottom)
		)
	)
	(text "MODE3"
		(exclude_from_sim no)
		(at 68.58 89.535 0)
		(effects
			(font
				(size 1.27 1.27)
			)
			(justify left bottom)
		)
	)
	(text "ALLPHYAD"
		(exclude_from_sim no)
		(at 68.58 108.585 0)
		(effects
			(font
				(size 1.27 1.27)
			)
			(justify left bottom)
		)
	)
	(text "NOTE:\nKSZ9131RNXC pins 13,14 and 47 connected \nfor backward compability with KSZ9031RNXC"
		(exclude_from_sim no)
		(at 14.605 26.67 0)
		(effects
			(font
				(size 1.27 1.27)
			)
			(justify left bottom)
		)
	)
	(text "~{INTSEL}"
		(exclude_from_sim no)
		(at 68.58 269.24 0)
		(effects
			(font
				(size 1.27 1.27)
			)
			(justify left bottom)
		)
	)
	(text "PHYAD0"
		(exclude_from_sim no)
		(at 68.58 260.985 0)
		(effects
			(font
				(size 1.27 1.27)
			)
			(justify left bottom)
		)
	)
	(text "PHYAD2"
		(exclude_from_sim no)
		(at 68.58 67.31 0)
		(effects
			(font
				(size 1.27 1.27)
			)
			(justify left bottom)
		)
	)
	(text "PHYAD2"
		(exclude_from_sim no)
		(at 68.58 100.965 0)
		(effects
			(font
				(size 1.27 1.27)
			)
			(justify left bottom)
		)
	)
	(text "PHYAD1"
		(exclude_from_sim no)
		(at 68.58 69.85 0)
		(effects
			(font
				(size 1.27 1.27)
			)
			(justify left bottom)
		)
	)
	(text "MODE0\n"
		(exclude_from_sim no)
		(at 68.58 63.5 0)
		(effects
			(font
				(size 1.27 1.27)
			)
			(justify left bottom)
		)
	)
	(text "NOTE:\nPlace close to AVDDL_PLL\n(PIN 44)"
		(exclude_from_sim no)
		(at 234.95 55.88 0)
		(effects
			(font
				(size 1.27 1.27)
			)
			(justify left bottom)
		)
	)
	(text "MODE2"
		(exclude_from_sim no)
		(at 68.58 58.42 0)
		(effects
			(font
				(size 1.27 1.27)
			)
			(justify left bottom)
		)
	)
	(text "MODE2"
		(exclude_from_sim no)
		(at 68.58 92.075 0)
		(effects
			(font
				(size 1.27 1.27)
			)
			(justify left bottom)
		)
	)
	(text "CLK125_EN"
		(exclude_from_sim no)
		(at 68.58 78.74 0)
		(effects
			(font
				(size 1.27 1.27)
			)
			(justify left bottom)
		)
	)
	(text "MODE0\n"
		(exclude_from_sim no)
		(at 68.58 233.045 0)
		(effects
			(font
				(size 1.27 1.27)
			)
			(justify left bottom)
		)
	)
	(text "REGOFF"
		(exclude_from_sim no)
		(at 68.58 240.665 0)
		(effects
			(font
				(size 1.27 1.27)
			)
			(justify left bottom)
		)
	)
	(text "Pull down"
		(exclude_from_sim no)
		(at 25.4 248.285 0)
		(effects
			(font
				(size 1.27 1.27)
			)
			(justify left bottom)
		)
	)
	(text "MODE0\n"
		(exclude_from_sim no)
		(at 68.58 97.155 0)
		(effects
			(font
				(size 1.27 1.27)
			)
			(justify left bottom)
		)
	)
	(text "MODE1"
		(exclude_from_sim no)
		(at 68.58 94.615 0)
		(effects
			(font
				(size 1.27 1.27)
			)
			(justify left bottom)
		)
	)
	(text "ALLPHYAD"
		(exclude_from_sim no)
		(at 68.58 74.93 0)
		(effects
			(font
				(size 1.27 1.27)
			)
			(justify left bottom)
		)
	)
	(text "CLK125_EN"
		(exclude_from_sim no)
		(at 68.58 112.395 0)
		(effects
			(font
				(size 1.27 1.27)
			)
			(justify left bottom)
		)
	)
	(text "NOTE:\nPlace close to HDMI connector"
		(exclude_from_sim no)
		(at 287.02 248.92 0)
		(effects
			(font
				(size 1.27 1.27)
			)
			(justify left bottom)
		)
	)
	(text "default:\nMODE[3:0] : 1100 (see datasheet table 3-8)\nPHYAD[4:0]: 00011 \nCLK125_EN: 0, disabled\nLED_MODE: 1, Individual-LED\nALLPHYAD: 1, disable (inverted logic)"
		(exclude_from_sim no)
		(at 19.685 132.715 0)
		(effects
			(font
				(size 1.27 1.27)
			)
			(justify left bottom)
		)
	)
	(text "PHYAD0"
		(exclude_from_sim no)
		(at 68.58 236.855 0)
		(effects
			(font
				(size 1.27 1.27)
			)
			(justify left bottom)
		)
	)
	(text "Ethernet"
		(exclude_from_sim no)
		(at 13.97 151.765 0)
		(effects
			(font
				(size 1.27 1.27)
				(thickness 0.4)
				(bold yes)
			)
			(justify left bottom)
		)
	)
	(text "Bootstrap configuration"
		(exclude_from_sim no)
		(at 19.685 48.26 0)
		(effects
			(font
				(size 1.27 1.27)
				(thickness 0.5994)
				(bold yes)
			)
			(justify left bottom)
		)
	)
	(text "HDMI"
		(exclude_from_sim no)
		(at 280.035 151.13 0)
		(effects
			(font
				(size 1.27 1.27)
				(thickness 0.4)
				(bold yes)
			)
			(justify left bottom)
		)
	)
	(text "PHYAD1"
		(exclude_from_sim no)
		(at 68.58 103.505 0)
		(effects
			(font
				(size 1.27 1.27)
			)
			(justify left bottom)
		)
	)
	(text "MODE1"
		(exclude_from_sim no)
		(at 68.58 230.505 0)
		(effects
			(font
				(size 1.27 1.27)
			)
			(justify left bottom)
		)
	)
	(text "NOTE:\nPlace close to FPGA"
		(exclude_from_sim no)
		(at 74.295 211.455 0)
		(effects
			(font
				(size 1.27 1.27)
			)
			(justify left bottom)
		)
	)
	(text "Gigabit Ethernet"
		(exclude_from_sim no)
		(at 14.605 18.415 0)
		(effects
			(font
				(size 1.27 1.27)
				(thickness 0.4)
				(bold yes)
			)
			(justify left bottom)
		)
	)
	(text "Bootstrap configuration"
		(exclude_from_sim no)
		(at 19.685 219.71 0)
		(effects
			(font
				(size 1.27 1.27)
				(thickness 0.5994)
				(bold yes)
			)
			(justify left bottom)
		)
	)
	(text "REGOFF"
		(exclude_from_sim no)
		(at 68.58 264.795 0)
		(effects
			(font
				(size 1.27 1.27)
			)
			(justify left bottom)
		)
	)
	(text "NOTE:\nPlace close ETH connector"
		(exclude_from_sim no)
		(at 242.57 213.995 0)
		(effects
			(font
				(size 1.27 1.27)
			)
			(justify left bottom)
		)
	)
	(text "MODE1"
		(exclude_from_sim no)
		(at 68.58 60.96 0)
		(effects
			(font
				(size 1.27 1.27)
			)
			(justify left bottom)
		)
	)
	(text "MODE2"
		(exclude_from_sim no)
		(at 68.58 227.965 0)
		(effects
			(font
				(size 1.27 1.27)
			)
			(justify left bottom)
		)
	)
	(text "NOTE:\nKSZ9131 allows \npairs and polarity swap"
		(exclude_from_sim no)
		(at 324.485 91.44 0)
		(effects
			(font
				(size 1.27 1.27)
			)
			(justify left bottom)
		)
	)
	(text "~{INTSEL}"
		(exclude_from_sim no)
		(at 68.58 245.11 0)
		(effects
			(font
				(size 1.27 1.27)
			)
			(justify left bottom)
		)
	)
	(text "Pull down"
		(exclude_from_sim no)
		(at 25.4 85.725 0)
		(effects
			(font
				(size 1.27 1.27)
			)
			(justify left bottom)
		)
	)
	(text "LED_MODE"
		(exclude_from_sim no)
		(at 68.58 81.28 0)
		(effects
			(font
				(size 1.27 1.27)
			)
			(justify left bottom)
		)
	)
	(junction
		(at 259.08 19.05)
		(diameter 0)
		(color 0 0 0 0)
	)
	(junction
		(at 130.81 19.05)
		(diameter 0)
		(color 0 0 0 0)
	)
	(junction
		(at 127 154.94)
		(diameter 0)
		(color 0 0 0 0)
	)
	(junction
		(at 208.28 208.28)
		(diameter 0)
		(color 0 0 0 0)
	)
	(junction
		(at 153.67 111.76)
		(diameter 0)
		(color 0 0 0 0)
	)
	(junction
		(at 68.58 78.74)
		(diameter 0)
		(color 0 0 0 0)
	)
	(junction
		(at 406.4 207.01)
		(diameter 0)
		(color 0 0 0 0)
	)
	(junction
		(at 68.58 93.98)
		(diameter 0)
		(color 0 0 0 0)
	)
	(junction
		(at 68.58 60.96)
		(diameter 0)
		(color 0 0 0 0)
	)
	(junction
		(at 195.58 154.94)
		(diameter 0)
		(color 0 0 0 0)
	)
	(junction
		(at 177.8 167.64)
		(diameter 0)
		(color 0 0 0 0)
	)
	(junction
		(at 246.38 179.07)
		(diameter 0)
		(color 0 0 0 0)
	)
	(junction
		(at 68.58 69.85)
		(diameter 0)
		(color 0 0 0 0)
	)
	(junction
		(at 68.58 111.76)
		(diameter 0)
		(color 0 0 0 0)
	)
	(junction
		(at 237.49 35.56)
		(diameter 0)
		(color 0 0 0 0)
	)
	(junction
		(at 111.76 55.88)
		(diameter 0)
		(color 0 0 0 0)
	)
	(junction
		(at 208.28 179.07)
		(diameter 0)
		(color 0 0 0 0)
	)
	(junction
		(at 327.66 19.05)
		(diameter 0)
		(color 0 0 0 0)
	)
	(junction
		(at 354.33 157.48)
		(diameter 0)
		(color 0 0 0 0)
	)
	(junction
		(at 120.65 19.05)
		(diameter 0)
		(color 0 0 0 0)
	)
	(junction
		(at 53.34 195.58)
		(diameter 0)
		(color 0 0 0 0)
	)
	(junction
		(at 246.38 198.12)
		(diameter 0)
		(color 0 0 0 0)
	)
	(junction
		(at 68.58 74.93)
		(diameter 0)
		(color 0 0 0 0)
	)
	(junction
		(at 142.24 35.56)
		(diameter 0)
		(color 0 0 0 0)
	)
	(junction
		(at 68.58 63.5)
		(diameter 0)
		(color 0 0 0 0)
	)
	(junction
		(at 120.65 35.56)
		(diameter 0)
		(color 0 0 0 0)
	)
	(junction
		(at 68.58 96.52)
		(diameter 0)
		(color 0 0 0 0)
	)
	(junction
		(at 106.68 220.98)
		(diameter 0)
		(color 0 0 0 0)
	)
	(junction
		(at 68.58 102.87)
		(diameter 0)
		(color 0 0 0 0)
	)
	(junction
		(at 406.4 212.09)
		(diameter 0)
		(color 0 0 0 0)
	)
	(junction
		(at 129.54 229.87)
		(diameter 0)
		(color 0 0 0 0)
	)
	(junction
		(at 269.24 35.56)
		(diameter 0)
		(color 0 0 0 0)
	)
	(junction
		(at 130.81 35.56)
		(diameter 0)
		(color 0 0 0 0)
	)
	(junction
		(at 153.67 120.65)
		(diameter 0)
		(color 0 0 0 0)
	)
	(junction
		(at 328.295 157.48)
		(diameter 0)
		(color 0 0 0 0)
	)
	(junction
		(at 280.67 19.05)
		(diameter 0)
		(color 0 0 0 0)
	)
	(junction
		(at 406.4 209.55)
		(diameter 0)
		(color 0 0 0 0)
	)
	(junction
		(at 68.58 55.88)
		(diameter 0)
		(color 0 0 0 0)
	)
	(junction
		(at 190.5 255.27)
		(diameter 0)
		(color 0 0 0 0)
	)
	(junction
		(at 406.4 214.63)
		(diameter 0)
		(color 0 0 0 0)
	)
	(junction
		(at 116.84 154.94)
		(diameter 0)
		(color 0 0 0 0)
	)
	(junction
		(at 68.58 240.03)
		(diameter 0)
		(color 0 0 0 0)
	)
	(junction
		(at 203.2 154.94)
		(diameter 0)
		(color 0 0 0 0)
	)
	(junction
		(at 68.58 232.41)
		(diameter 0)
		(color 0 0 0 0)
	)
	(junction
		(at 142.24 19.05)
		(diameter 0)
		(color 0 0 0 0)
	)
	(junction
		(at 269.24 19.05)
		(diameter 0)
		(color 0 0 0 0)
	)
	(junction
		(at 124.46 120.65)
		(diameter 0)
		(color 0 0 0 0)
	)
	(junction
		(at 290.83 19.05)
		(diameter 0)
		(color 0 0 0 0)
	)
	(junction
		(at 152.4 19.05)
		(diameter 0)
		(color 0 0 0 0)
	)
	(junction
		(at 250.19 265.43)
		(diameter 0)
		(color 0 0 0 0)
	)
	(junction
		(at 247.65 154.94)
		(diameter 0)
		(color 0 0 0 0)
	)
	(junction
		(at 317.5 19.05)
		(diameter 0)
		(color 0 0 0 0)
	)
	(junction
		(at 144.78 120.65)
		(diameter 0)
		(color 0 0 0 0)
	)
	(junction
		(at 220.98 154.94)
		(diameter 0)
		(color 0 0 0 0)
	)
	(junction
		(at 129.54 220.98)
		(diameter 0)
		(color 0 0 0 0)
	)
	(junction
		(at 233.68 179.07)
		(diameter 0)
		(color 0 0 0 0)
	)
	(junction
		(at 220.98 208.28)
		(diameter 0)
		(color 0 0 0 0)
	)
	(junction
		(at 114.3 19.05)
		(diameter 0)
		(color 0 0 0 0)
	)
	(junction
		(at 68.58 229.87)
		(diameter 0)
		(color 0 0 0 0)
	)
	(junction
		(at 68.58 236.22)
		(diameter 0)
		(color 0 0 0 0)
	)
	(junction
		(at 312.42 157.48)
		(diameter 0)
		(color 0 0 0 0)
	)
	(junction
		(at 233.68 195.58)
		(diameter 0)
		(color 0 0 0 0)
	)
	(junction
		(at 68.58 105.41)
		(diameter 0)
		(color 0 0 0 0)
	)
	(junction
		(at 327.66 35.56)
		(diameter 0)
		(color 0 0 0 0)
	)
	(junction
		(at 220.98 179.07)
		(diameter 0)
		(color 0 0 0 0)
	)
	(junction
		(at 68.58 91.44)
		(diameter 0)
		(color 0 0 0 0)
	)
	(junction
		(at 68.58 264.16)
		(diameter 0)
		(color 0 0 0 0)
	)
	(junction
		(at 68.58 114.3)
		(diameter 0)
		(color 0 0 0 0)
	)
	(junction
		(at 184.15 154.94)
		(diameter 0)
		(color 0 0 0 0)
	)
	(junction
		(at 68.58 72.39)
		(diameter 0)
		(color 0 0 0 0)
	)
	(junction
		(at 223.52 38.1)
		(diameter 0)
		(color 0 0 0 0)
	)
	(junction
		(at 280.67 35.56)
		(diameter 0)
		(color 0 0 0 0)
	)
	(junction
		(at 114.3 35.56)
		(diameter 0)
		(color 0 0 0 0)
	)
	(junction
		(at 68.58 227.33)
		(diameter 0)
		(color 0 0 0 0)
	)
	(junction
		(at 317.5 35.56)
		(diameter 0)
		(color 0 0 0 0)
	)
	(junction
		(at 68.58 256.54)
		(diameter 0)
		(color 0 0 0 0)
	)
	(junction
		(at 68.58 267.97)
		(diameter 0)
		(color 0 0 0 0)
	)
	(junction
		(at 68.58 58.42)
		(diameter 0)
		(color 0 0 0 0)
	)
	(junction
		(at 223.52 114.3)
		(diameter 0)
		(color 0 0 0 0)
	)
	(junction
		(at 237.49 19.05)
		(diameter 0)
		(color 0 0 0 0)
	)
	(junction
		(at 220.98 193.04)
		(diameter 0)
		(color 0 0 0 0)
	)
	(junction
		(at 247.65 35.56)
		(diameter 0)
		(color 0 0 0 0)
	)
	(junction
		(at 172.72 45.72)
		(diameter 0)
		(color 0 0 0 0)
	)
	(junction
		(at 259.08 35.56)
		(diameter 0)
		(color 0 0 0 0)
	)
	(junction
		(at 106.68 229.87)
		(diameter 0)
		(color 0 0 0 0)
	)
	(junction
		(at 68.58 67.31)
		(diameter 0)
		(color 0 0 0 0)
	)
	(junction
		(at 21.59 172.72)
		(diameter 0)
		(color 0 0 0 0)
	)
	(junction
		(at 247.65 19.05)
		(diameter 0)
		(color 0 0 0 0)
	)
	(junction
		(at 233.68 208.28)
		(diameter 0)
		(color 0 0 0 0)
	)
	(junction
		(at 68.58 100.33)
		(diameter 0)
		(color 0 0 0 0)
	)
	(junction
		(at 68.58 260.35)
		(diameter 0)
		(color 0 0 0 0)
	)
	(junction
		(at 406.4 217.17)
		(diameter 0)
		(color 0 0 0 0)
	)
	(junction
		(at 208.28 190.5)
		(diameter 0)
		(color 0 0 0 0)
	)
	(junction
		(at 227.33 45.72)
		(diameter 0)
		(color 0 0 0 0)
	)
	(junction
		(at 152.4 35.56)
		(diameter 0)
		(color 0 0 0 0)
	)
	(junction
		(at 184.15 172.72)
		(diameter 0)
		(color 0 0 0 0)
	)
	(junction
		(at 68.58 107.95)
		(diameter 0)
		(color 0 0 0 0)
	)
	(junction
		(at 68.58 254)
		(diameter 0)
		(color 0 0 0 0)
	)
	(no_connect
		(at 219.71 53.34)
	)
	(no_connect
		(at 217.17 247.65)
	)
	(no_connect
		(at 379.73 209.55)
	)
	(no_connect
		(at 379.73 199.39)
	)
	(no_connect
		(at 379.73 212.09)
	)
	(no_connect
		(at 379.73 196.85)
	)
	(no_connect
		(at 217.17 250.19)
	)
	(no_connect
		(at 217.17 252.73)
	)
	(no_connect
		(at 379.73 204.47)
	)
	(no_connect
		(at 217.17 245.11)
	)
	(bus_entry
		(at 53.34 191.77)
		(size 1.27 -1.27)
		(stroke
			(width 0)
			(type default)
		)
	)
	(bus_entry
		(at 148.59 66.04)
		(size 1.27 1.27)
		(stroke
			(width 0)
			(type default)
		)
	)
	(bus_entry
		(at 201.93 260.35)
		(size -1.27 1.27)
		(stroke
			(width 0)
			(type default)
		)
	)
	(bus_entry
		(at 320.04 173.99)
		(size -1.27 1.27)
		(stroke
			(width 0)
			(type default)
		)
	)
	(bus_entry
		(at 336.55 128.27)
		(size -1.27 1.27)
		(stroke
			(width 0)
			(type default)
		)
	)
	(bus_entry
		(at 148.59 55.88)
		(size 1.27 1.27)
		(stroke
			(width 0)
			(type default)
		)
	)
	(bus_entry
		(at 54.61 172.72)
		(size -1.27 1.27)
		(stroke
			(width 0)
			(type default)
		)
	)
	(bus_entry
		(at 151.13 71.12)
		(size -1.27 1.27)
		(stroke
			(width 0)
			(type default)
		)
	)
	(bus_entry
		(at 151.13 73.66)
		(size -1.27 1.27)
		(stroke
			(width 0)
			(type default)
		)
	)
	(bus_entry
		(at 54.61 180.34)
		(size -1.27 1.27)
		(stroke
			(width 0)
			(type default)
		)
	)
	(bus_entry
		(at 53.34 196.85)
		(size 1.27 1.27)
		(stroke
			(width 0)
			(type default)
		)
	)
	(bus_entry
		(at 320.04 181.61)
		(size -1.27 1.27)
		(stroke
			(width 0)
			(type default)
		)
	)
	(bus_entry
		(at 53.34 199.39)
		(size 1.27 1.27)
		(stroke
			(width 0)
			(type default)
		)
	)
	(bus_entry
		(at 52.07 172.72)
		(size 1.27 1.27)
		(stroke
			(width 0)
			(type default)
		)
	)
	(bus_entry
		(at 320.04 171.45)
		(size -1.27 1.27)
		(stroke
			(width 0)
			(type default)
		)
	)
	(bus_entry
		(at 201.93 267.97)
		(size -1.27 1.27)
		(stroke
			(width 0)
			(type default)
		)
	)
	(bus_entry
		(at 53.34 201.93)
		(size 1.27 1.27)
		(stroke
			(width 0)
			(type default)
		)
	)
	(bus_entry
		(at 151.13 63.5)
		(size -1.27 1.27)
		(stroke
			(width 0)
			(type default)
		)
	)
	(bus_entry
		(at 149.86 100.33)
		(size 1.27 1.27)
		(stroke
			(width 0)
			(type default)
		)
	)
	(bus_entry
		(at 336.55 123.19)
		(size -1.27 1.27)
		(stroke
			(width 0)
			(type default)
		)
	)
	(bus_entry
		(at 151.13 76.2)
		(size -1.27 1.27)
		(stroke
			(width 0)
			(type default)
		)
	)
	(bus_entry
		(at 53.34 194.31)
		(size 1.27 -1.27)
		(stroke
			(width 0)
			(type default)
		)
	)
	(bus_entry
		(at 54.61 175.26)
		(size -1.27 1.27)
		(stroke
			(width 0)
			(type default)
		)
	)
	(bus_entry
		(at 149.86 92.71)
		(size 1.27 1.27)
		(stroke
			(width 0)
			(type default)
		)
	)
	(bus_entry
		(at 151.13 66.04)
		(size -1.27 1.27)
		(stroke
			(width 0)
			(type default)
		)
	)
	(bus_entry
		(at 151.13 55.88)
		(size -1.27 1.27)
		(stroke
			(width 0)
			(type default)
		)
	)
	(bus_entry
		(at 201.93 262.89)
		(size -1.27 1.27)
		(stroke
			(width 0)
			(type default)
		)
	)
	(bus_entry
		(at 320.04 176.53)
		(size -1.27 1.27)
		(stroke
			(width 0)
			(type default)
		)
	)
	(bus_entry
		(at 336.55 125.73)
		(size -1.27 1.27)
		(stroke
			(width 0)
			(type default)
		)
	)
	(bus_entry
		(at 320.04 166.37)
		(size -1.27 1.27)
		(stroke
			(width 0)
			(type default)
		)
	)
	(bus_entry
		(at 54.61 182.88)
		(size -1.27 1.27)
		(stroke
			(width 0)
			(type default)
		)
	)
	(bus_entry
		(at 151.13 81.28)
		(size -1.27 1.27)
		(stroke
			(width 0)
			(type default)
		)
	)
	(bus_entry
		(at 149.86 95.25)
		(size 1.27 1.27)
		(stroke
			(width 0)
			(type default)
		)
	)
	(bus_entry
		(at 149.86 87.63)
		(size 1.27 1.27)
		(stroke
			(width 0)
			(type default)
		)
	)
	(bus_entry
		(at 148.59 66.04)
		(size 1.27 1.27)
		(stroke
			(width 0)
			(type default)
		)
	)
	(bus_entry
		(at 320.04 179.07)
		(size -1.27 1.27)
		(stroke
			(width 0)
			(type default)
		)
	)
	(bus_entry
		(at 151.13 78.74)
		(size -1.27 1.27)
		(stroke
			(width 0)
			(type default)
		)
	)
	(bus_entry
		(at 52.07 180.34)
		(size 1.27 1.27)
		(stroke
			(width 0)
			(type default)
		)
	)
	(bus_entry
		(at 52.07 180.34)
		(size 1.27 1.27)
		(stroke
			(width 0)
			(type default)
		)
	)
	(bus_entry
		(at 201.93 265.43)
		(size -1.27 1.27)
		(stroke
			(width 0)
			(type default)
		)
	)
	(bus_entry
		(at 336.55 120.65)
		(size -1.27 1.27)
		(stroke
			(width 0)
			(type default)
		)
	)
	(bus_entry
		(at 149.86 105.41)
		(size 1.27 1.27)
		(stroke
			(width 0)
			(type default)
		)
	)
	(bus_entry
		(at 53.34 204.47)
		(size 1.27 1.27)
		(stroke
			(width 0)
			(type default)
		)
	)
	(bus_entry
		(at 53.34 189.23)
		(size 1.27 -1.27)
		(stroke
			(width 0)
			(type default)
		)
	)
	(bus_entry
		(at 149.86 90.17)
		(size 1.27 1.27)
		(stroke
			(width 0)
			(type default)
		)
	)
	(bus_entry
		(at 151.13 83.82)
		(size -1.27 1.27)
		(stroke
			(width 0)
			(type default)
		)
	)
	(bus_entry
		(at 320.04 184.15)
		(size -1.27 1.27)
		(stroke
			(width 0)
			(type default)
		)
	)
	(bus_entry
		(at 151.13 58.42)
		(size -1.27 1.27)
		(stroke
			(width 0)
			(type default)
		)
	)
	(bus_entry
		(at 149.86 97.79)
		(size 1.27 1.27)
		(stroke
			(width 0)
			(type default)
		)
	)
	(bus_entry
		(at 320.04 168.91)
		(size -1.27 1.27)
		(stroke
			(width 0)
			(type default)
		)
	)
	(bus_entry
		(at 151.13 58.42)
		(size -1.27 1.27)
		(stroke
			(width 0)
			(type default)
		)
	)
	(wire
		(pts
			(xy 320.04 176.53) (xy 342.9 176.53)
		)
		(stroke
			(width 0)
			(type default)
		)
	)
	(wire
		(pts
			(xy 219.71 109.22) (xy 229.87 109.22)
		)
		(stroke
			(width 0)
			(type default)
		)
	)
	(bus
		(pts
			(xy 53.34 195.58) (xy 53.34 196.85)
		)
		(stroke
			(width 0)
			(type default)
		)
	)
	(wire
		(pts
			(xy 317.5 19.05) (xy 317.5 21.59)
		)
		(stroke
			(width 0)
			(type default)
		)
	)
	(wire
		(pts
			(xy 52.07 93.98) (xy 25.4 93.98)
		)
		(stroke
			(width 0)
			(type default)
		)
	)
	(wire
		(pts
			(xy 320.04 181.61) (xy 342.9 181.61)
		)
		(stroke
			(width 0)
			(type default)
		)
	)
	(wire
		(pts
			(xy 184.15 162.56) (xy 184.15 163.83)
		)
		(stroke
			(width 0)
			(type default)
		)
	)
	(wire
		(pts
			(xy 120.65 35.56) (xy 130.81 35.56)
		)
		(stroke
			(width 0)
			(type default)
		)
	)
	(wire
		(pts
			(xy 196.85 240.03) (xy 217.17 240.03)
		)
		(stroke
			(width 0)
			(type default)
		)
	)
	(wire
		(pts
			(xy 233.68 200.66) (xy 233.68 195.58)
		)
		(stroke
			(width 0)
			(type default)
		)
	)
	(wire
		(pts
			(xy 406.4 207.01) (xy 406.4 209.55)
		)
		(stroke
			(width 0)
			(type default)
		)
	)
	(wire
		(pts
			(xy 54.61 200.66) (xy 105.41 200.66)
		)
		(stroke
			(width 0)
			(type default)
		)
	)
	(bus
		(pts
			(xy 149.86 95.25) (xy 149.86 97.79)
		)
		(stroke
			(width 0)
			(type default)
		)
	)
	(wire
		(pts
			(xy 396.24 90.17) (xy 396.24 92.71)
		)
		(stroke
			(width 0)
			(type default)
		)
	)
	(wire
		(pts
			(xy 203.2 154.94) (xy 203.2 179.07)
		)
		(stroke
			(width 0)
			(type default)
		)
	)
	(polyline
		(pts
			(xy 82.55 133.35) (xy 19.05 133.35)
		)
		(stroke
			(width 0)
			(type solid)
		)
	)
	(wire
		(pts
			(xy 289.56 205.74) (xy 311.15 205.74)
		)
		(stroke
			(width 0)
			(type default)
		)
	)
	(wire
		(pts
			(xy 233.68 208.28) (xy 246.38 208.28)
		)
		(stroke
			(width 0)
			(type default)
		)
	)
	(wire
		(pts
			(xy 312.42 166.37) (xy 312.42 168.91)
		)
		(stroke
			(width 0)
			(type default)
		)
	)
	(wire
		(pts
			(xy 247.65 19.05) (xy 237.49 19.05)
		)
		(stroke
			(width 0)
			(type default)
		)
	)
	(wire
		(pts
			(xy 127 154.94) (xy 127 157.48)
		)
		(stroke
			(width 0)
			(type default)
		)
	)
	(wire
		(pts
			(xy 237.49 35.56) (xy 237.49 38.1)
		)
		(stroke
			(width 0)
			(type default)
		)
	)
	(wire
		(pts
			(xy 68.58 267.97) (xy 68.58 270.51)
		)
		(stroke
			(width 0)
			(type default)
		)
	)
	(wire
		(pts
			(xy 347.98 181.61) (xy 374.65 181.61)
		)
		(stroke
			(width 0)
			(type default)
		)
	)
	(wire
		(pts
			(xy 347.98 173.99) (xy 378.46 173.99)
		)
		(stroke
			(width 0)
			(type default)
		)
	)
	(wire
		(pts
			(xy 320.04 173.99) (xy 342.9 173.99)
		)
		(stroke
			(width 0)
			(type default)
		)
	)
	(polyline
		(pts
			(xy 205.74 173.99) (xy 269.24 173.99)
		)
		(stroke
			(width 0)
			(type default)
		)
	)
	(wire
		(pts
			(xy 247.65 43.18) (xy 247.65 44.45)
		)
		(stroke
			(width 0)
			(type default)
		)
	)
	(wire
		(pts
			(xy 127 162.56) (xy 127 163.83)
		)
		(stroke
			(width 0)
			(type default)
		)
	)
	(wire
		(pts
			(xy 250.19 273.05) (xy 250.19 275.59)
		)
		(stroke
			(width 0)
			(type default)
		)
	)
	(wire
		(pts
			(xy 227.33 45.72) (xy 227.33 35.56)
		)
		(stroke
			(width 0)
			(type default)
		)
	)
	(wire
		(pts
			(xy 201.93 260.35) (xy 217.17 260.35)
		)
		(stroke
			(width 0)
			(type default)
		)
	)
	(wire
		(pts
			(xy 220.98 208.28) (xy 233.68 208.28)
		)
		(stroke
			(width 0)
			(type default)
		)
	)
	(wire
		(pts
			(xy 379.73 171.45) (xy 379.73 173.99)
		)
		(stroke
			(width 0)
			(type default)
		)
	)
	(wire
		(pts
			(xy 130.81 19.05) (xy 142.24 19.05)
		)
		(stroke
			(width 0)
			(type default)
		)
	)
	(wire
		(pts
			(xy 124.46 129.54) (xy 124.46 132.08)
		)
		(stroke
			(width 0)
			(type default)
		)
	)
	(wire
		(pts
			(xy 237.49 26.67) (xy 237.49 29.21)
		)
		(stroke
			(width 0)
			(type default)
		)
	)
	(bus
		(pts
			(xy 53.34 196.85) (xy 53.34 199.39)
		)
		(stroke
			(width 0)
			(type default)
		)
	)
	(wire
		(pts
			(xy 405.13 209.55) (xy 406.4 209.55)
		)
		(stroke
			(width 0)
			(type default)
		)
	)
	(wire
		(pts
			(xy 227.33 45.72) (xy 227.33 48.26)
		)
		(stroke
			(width 0)
			(type default)
		)
	)
	(wire
		(pts
			(xy 175.26 215.9) (xy 177.8 215.9)
		)
		(stroke
			(width 0)
			(type default)
		)
	)
	(wire
		(pts
			(xy 54.61 193.04) (xy 81.28 193.04)
		)
		(stroke
			(width 0)
			(type default)
		)
	)
	(wire
		(pts
			(xy 175.26 208.28) (xy 191.77 208.28)
		)
		(stroke
			(width 0)
			(type default)
		)
	)
	(polyline
		(pts
			(xy 13.97 139.7) (xy 406.4 139.7)
		)
		(stroke
			(width 0)
			(type default)
		)
	)
	(wire
		(pts
			(xy 373.38 191.77) (xy 373.38 184.15)
		)
		(stroke
			(width 0)
			(type default)
		)
	)
	(wire
		(pts
			(xy 354.33 157.48) (xy 354.33 217.17)
		)
		(stroke
			(width 0)
			(type default)
		)
	)
	(wire
		(pts
			(xy 229.87 109.22) (xy 229.87 110.49)
		)
		(stroke
			(width 0)
			(type default)
		)
	)
	(wire
		(pts
			(xy 129.54 229.87) (xy 129.54 233.68)
		)
		(stroke
			(width 0)
			(type default)
		)
	)
	(wire
		(pts
			(xy 280.67 19.05) (xy 280.67 21.59)
		)
		(stroke
			(width 0)
			(type default)
		)
	)
	(bus
		(pts
			(xy 149.86 64.77) (xy 149.86 67.31)
		)
		(stroke
			(width 0)
			(type default)
		)
	)
	(polyline
		(pts
			(xy 19.05 215.9) (xy 19.05 280.67)
		)
		(stroke
			(width 0)
			(type default)
		)
	)
	(wire
		(pts
			(xy 111.76 55.88) (xy 111.76 66.04)
		)
		(stroke
			(width 0)
			(type default)
		)
	)
	(polyline
		(pts
			(xy 119.38 171.45) (xy 119.38 212.09)
		)
		(stroke
			(width 0)
			(type default)
		)
	)
	(wire
		(pts
			(xy 405.13 212.09) (xy 406.4 212.09)
		)
		(stroke
			(width 0)
			(type default)
		)
	)
	(wire
		(pts
			(xy 106.68 220.98) (xy 106.68 229.87)
		)
		(stroke
			(width 0)
			(type default)
		)
	)
	(wire
		(pts
			(xy 246.38 198.12) (xy 266.7 198.12)
		)
		(stroke
			(width 0)
			(type default)
		)
	)
	(wire
		(pts
			(xy 354.33 217.17) (xy 379.73 217.17)
		)
		(stroke
			(width 0)
			(type default)
		)
	)
	(wire
		(pts
			(xy 110.49 198.12) (xy 137.16 198.12)
		)
		(stroke
			(width 0)
			(type default)
		)
	)
	(bus
		(pts
			(xy 53.34 194.31) (xy 53.34 195.58)
		)
		(stroke
			(width 0)
			(type default)
		)
	)
	(bus
		(pts
			(xy 335.28 124.46) (xy 335.28 121.92)
		)
		(stroke
			(width 0)
			(type default)
		)
	)
	(wire
		(pts
			(xy 219.71 96.52) (xy 238.76 96.52)
		)
		(stroke
			(width 0)
			(type default)
		)
	)
	(wire
		(pts
			(xy 223.52 19.05) (xy 237.49 19.05)
		)
		(stroke
			(width 0)
			(type default)
		)
	)
	(wire
		(pts
			(xy 247.65 154.94) (xy 247.65 157.48)
		)
		(stroke
			(width 0)
			(type default)
		)
	)
	(polyline
		(pts
			(xy 73.66 184.15) (xy 95.25 184.15)
		)
		(stroke
			(width 0)
			(type default)
		)
	)
	(wire
		(pts
			(xy 57.15 240.03) (xy 68.58 240.03)
		)
		(stroke
			(width 0)
			(type default)
		)
	)
	(wire
		(pts
			(xy 175.26 170.18) (xy 177.8 170.18)
		)
		(stroke
			(width 0)
			(type default)
		)
	)
	(wire
		(pts
			(xy 259.08 35.56) (xy 259.08 38.1)
		)
		(stroke
			(width 0)
			(type default)
		)
	)
	(wire
		(pts
			(xy 336.55 123.19) (xy 351.79 123.19)
		)
		(stroke
			(width 0)
			(type default)
		)
	)
	(polyline
		(pts
			(xy 273.05 284.48) (xy 273.05 146.05)
		)
		(stroke
			(width 0)
			(type default)
		)
	)
	(bus
		(pts
			(xy 53.34 184.15) (xy 53.34 189.23)
		)
		(stroke
			(width 0)
			(type default)
		)
	)
	(wire
		(pts
			(xy 327.66 19.05) (xy 332.74 19.05)
		)
		(stroke
			(width 0)
			(type default)
		)
	)
	(bus
		(pts
			(xy 200.66 269.24) (xy 200.66 266.7)
		)
		(stroke
			(width 0)
			(type default)
		)
	)
	(wire
		(pts
			(xy 116.84 66.04) (xy 111.76 66.04)
		)
		(stroke
			(width 0)
			(type default)
		)
	)
	(wire
		(pts
			(xy 331.47 102.87) (xy 351.79 102.87)
		)
		(stroke
			(width 0)
			(type default)
		)
	)
	(wire
		(pts
			(xy 354.33 157.48) (xy 356.87 157.48)
		)
		(stroke
			(width 0)
			(type default)
		)
	)
	(wire
		(pts
			(xy 396.24 114.3) (xy 396.24 111.76)
		)
		(stroke
			(width 0)
			(type default)
		)
	)
	(wire
		(pts
			(xy 280.67 26.67) (xy 280.67 29.21)
		)
		(stroke
			(width 0)
			(type default)
		)
	)
	(wire
		(pts
			(xy 406.4 217.17) (xy 406.4 222.25)
		)
		(stroke
			(width 0)
			(type default)
		)
	)
	(bus
		(pts
			(xy 40.64 195.58) (xy 53.34 195.58)
		)
		(stroke
			(width 0)
			(type default)
		)
	)
	(wire
		(pts
			(xy 110.49 153.67) (xy 110.49 154.94)
		)
		(stroke
			(width 0)
			(type default)
		)
	)
	(wire
		(pts
			(xy 406.4 217.17) (xy 405.13 217.17)
		)
		(stroke
			(width 0)
			(type default)
		)
	)
	(wire
		(pts
			(xy 52.07 180.34) (xy 30.48 180.34)
		)
		(stroke
			(width 0)
			(type default)
		)
	)
	(wire
		(pts
			(xy 130.81 120.65) (xy 124.46 120.65)
		)
		(stroke
			(width 0)
			(type default)
		)
	)
	(wire
		(pts
			(xy 25.4 74.93) (xy 52.07 74.93)
		)
		(stroke
			(width 0)
			(type default)
		)
	)
	(bus
		(pts
			(xy 318.77 177.8) (xy 318.77 180.34)
		)
		(stroke
			(width 0)
			(type default)
		)
	)
	(wire
		(pts
			(xy 269.24 43.18) (xy 269.24 44.45)
		)
		(stroke
			(width 0)
			(type default)
		)
	)
	(wire
		(pts
			(xy 247.65 35.56) (xy 247.65 38.1)
		)
		(stroke
			(width 0)
			(type default)
		)
	)
	(wire
		(pts
			(xy 25.4 55.88) (xy 52.07 55.88)
		)
		(stroke
			(width 0)
			(type default)
		)
	)
	(wire
		(pts
			(xy 175.26 193.04) (xy 220.98 193.04)
		)
		(stroke
			(width 0)
			(type default)
		)
	)
	(wire
		(pts
			(xy 220.98 193.04) (xy 220.98 200.66)
		)
		(stroke
			(width 0)
			(type default)
		)
	)
	(wire
		(pts
			(xy 68.58 256.54) (xy 68.58 260.35)
		)
		(stroke
			(width 0)
			(type default)
		)
	)
	(wire
		(pts
			(xy 120.65 35.56) (xy 120.65 38.1)
		)
		(stroke
			(width 0)
			(type default)
		)
	)
	(wire
		(pts
			(xy 347.98 166.37) (xy 379.73 166.37)
		)
		(stroke
			(width 0)
			(type default)
		)
	)
	(polyline
		(pts
			(xy 233.68 34.29) (xy 265.43 34.29)
		)
		(stroke
			(width 0)
			(type default)
		)
	)
	(wire
		(pts
			(xy 245.11 267.97) (xy 245.11 275.59)
		)
		(stroke
			(width 0)
			(type default)
		)
	)
	(bus
		(pts
			(xy 318.77 186.69) (xy 317.5 187.96)
		)
		(stroke
			(width 0)
			(type default)
		)
	)
	(wire
		(pts
			(xy 106.68 19.05) (xy 114.3 19.05)
		)
		(stroke
			(width 0)
			(type default)
		)
	)
	(wire
		(pts
			(xy 250.19 265.43) (xy 261.62 265.43)
		)
		(stroke
			(width 0)
			(type default)
		)
	)
	(wire
		(pts
			(xy 151.13 83.82) (xy 175.26 83.82)
		)
		(stroke
			(width 0)
			(type default)
		)
	)
	(bus
		(pts
			(xy 318.77 170.18) (xy 318.77 172.72)
		)
		(stroke
			(width 0)
			(type default)
		)
	)
	(wire
		(pts
			(xy 227.33 35.56) (xy 237.49 35.56)
		)
		(stroke
			(width 0)
			(type default)
		)
	)
	(wire
		(pts
			(xy 86.36 190.5) (xy 137.16 190.5)
		)
		(stroke
			(width 0)
			(type default)
		)
	)
	(polyline
		(pts
			(xy 96.52 212.09) (xy 119.38 212.09)
		)
		(stroke
			(width 0)
			(type default)
		)
	)
	(wire
		(pts
			(xy 57.15 81.28) (xy 68.58 81.28)
		)
		(stroke
			(width 0)
			(type default)
		)
	)
	(wire
		(pts
			(xy 219.71 45.72) (xy 227.33 45.72)
		)
		(stroke
			(width 0)
			(type default)
		)
	)
	(polyline
		(pts
			(xy 82.55 215.9) (xy 82.55 280.67)
		)
		(stroke
			(width 0)
			(type solid)
		)
	)
	(wire
		(pts
			(xy 219.71 76.2) (xy 232.41 76.2)
		)
		(stroke
			(width 0)
			(type default)
		)
	)
	(wire
		(pts
			(xy 243.84 265.43) (xy 250.19 265.43)
		)
		(stroke
			(width 0)
			(type default)
		)
	)
	(wire
		(pts
			(xy 246.38 179.07) (xy 246.38 181.61)
		)
		(stroke
			(width 0)
			(type default)
		)
	)
	(wire
		(pts
			(xy 54.61 187.96) (xy 81.28 187.96)
		)
		(stroke
			(width 0)
			(type default)
		)
	)
	(wire
		(pts
			(xy 219.71 68.58) (xy 232.41 68.58)
		)
		(stroke
			(width 0)
			(type default)
		)
	)
	(polyline
		(pts
			(xy 82.55 280.67) (xy 19.05 280.67)
		)
		(stroke
			(width 0)
			(type default)
		)
	)
	(wire
		(pts
			(xy 152.4 35.56) (xy 168.91 35.56)
		)
		(stroke
			(width 0)
			(type default)
		)
	)
	(wire
		(pts
			(xy 405.13 214.63) (xy 406.4 214.63)
		)
		(stroke
			(width 0)
			(type default)
		)
	)
	(polyline
		(pts
			(xy 323.85 85.09) (xy 349.25 85.09)
		)
		(stroke
			(width 0)
			(type default)
		)
	)
	(wire
		(pts
			(xy 52.07 254) (xy 25.4 254)
		)
		(stroke
			(width 0)
			(type default)
		)
	)
	(wire
		(pts
			(xy 208.28 208.28) (xy 220.98 208.28)
		)
		(stroke
			(width 0)
			(type default)
		)
	)
	(polyline
		(pts
			(xy 345.44 250.19) (xy 285.75 250.19)
		)
		(stroke
			(width 0)
			(type default)
		)
	)
	(bus
		(pts
			(xy 318.77 172.72) (xy 318.77 175.26)
		)
		(stroke
			(width 0)
			(type default)
		)
	)
	(wire
		(pts
			(xy 68.58 69.85) (xy 68.58 72.39)
		)
		(stroke
			(width 0)
			(type default)
		)
	)
	(bus
		(pts
			(xy 149.86 92.71) (xy 149.86 95.25)
		)
		(stroke
			(width 0)
			(type default)
		)
	)
	(wire
		(pts
			(xy 57.15 69.85) (xy 68.58 69.85)
		)
		(stroke
			(width 0)
			(type default)
		)
	)
	(wire
		(pts
			(xy 208.28 208.28) (xy 208.28 209.55)
		)
		(stroke
			(width 0)
			(type default)
		)
	)
	(wire
		(pts
			(xy 247.65 26.67) (xy 247.65 29.21)
		)
		(stroke
			(width 0)
			(type default)
		)
	)
	(wire
		(pts
			(xy 184.15 154.94) (xy 195.58 154.94)
		)
		(stroke
			(width 0)
			(type default)
		)
	)
	(wire
		(pts
			(xy 184.15 180.34) (xy 184.15 182.88)
		)
		(stroke
			(width 0)
			(type default)
		)
	)
	(wire
		(pts
			(xy 25.4 243.84) (xy 52.07 243.84)
		)
		(stroke
			(width 0)
			(type default)
		)
	)
	(wire
		(pts
			(xy 196.85 237.49) (xy 217.17 237.49)
		)
		(stroke
			(width 0)
			(type default)
		)
	)
	(wire
		(pts
			(xy 25.4 63.5) (xy 52.07 63.5)
		)
		(stroke
			(width 0)
			(type default)
		)
	)
	(wire
		(pts
			(xy 106.68 220.98) (xy 116.84 220.98)
		)
		(stroke
			(width 0)
			(type default)
		)
	)
	(wire
		(pts
			(xy 243.84 267.97) (xy 245.11 267.97)
		)
		(stroke
			(width 0)
			(type default)
		)
	)
	(wire
		(pts
			(xy 223.52 38.1) (xy 223.52 40.64)
		)
		(stroke
			(width 0)
			(type default)
		)
	)
	(wire
		(pts
			(xy 57.15 232.41) (xy 68.58 232.41)
		)
		(stroke
			(width 0)
			(type default)
		)
	)
	(wire
		(pts
			(xy 57.15 105.41) (xy 68.58 105.41)
		)
		(stroke
			(width 0)
			(type default)
		)
	)
	(wire
		(pts
			(xy 68.58 63.5) (xy 68.58 67.31)
		)
		(stroke
			(width 0)
			(type default)
		)
	)
	(wire
		(pts
			(xy 320.04 166.37) (xy 342.9 166.37)
		)
		(stroke
			(width 0)
			(type default)
		)
	)
	(wire
		(pts
			(xy 151.13 58.42) (xy 175.26 58.42)
		)
		(stroke
			(width 0)
			(type default)
		)
	)
	(wire
		(pts
			(xy 21.59 172.72) (xy 25.4 172.72)
		)
		(stroke
			(width 0)
			(type default)
		)
	)
	(wire
		(pts
			(xy 195.58 154.94) (xy 203.2 154.94)
		)
		(stroke
			(width 0)
			(type default)
		)
	)
	(wire
		(pts
			(xy 378.46 109.855) (xy 393.7 109.855)
		)
		(stroke
			(width 0)
			(type default)
		)
	)
	(wire
		(pts
			(xy 262.89 245.11) (xy 262.89 247.65)
		)
		(stroke
			(width 0)
			(type default)
		)
	)
	(wire
		(pts
			(xy 208.28 190.5) (xy 208.28 200.66)
		)
		(stroke
			(width 0)
			(type default)
		)
	)
	(bus
		(pts
			(xy 200.66 266.7) (xy 200.66 264.16)
		)
		(stroke
			(width 0)
			(type default)
		)
	)
	(wire
		(pts
			(xy 68.58 264.16) (xy 68.58 267.97)
		)
		(stroke
			(width 0)
			(type default)
		)
	)
	(wire
		(pts
			(xy 262.89 239.395) (xy 262.89 237.49)
		)
		(stroke
			(width 0)
			(type default)
		)
	)
	(wire
		(pts
			(xy 57.15 256.54) (xy 68.58 256.54)
		)
		(stroke
			(width 0)
			(type default)
		)
	)
	(wire
		(pts
			(xy 280.67 35.56) (xy 317.5 35.56)
		)
		(stroke
			(width 0)
			(type default)
		)
	)
	(wire
		(pts
			(xy 208.28 190.5) (xy 266.7 190.5)
		)
		(stroke
			(width 0)
			(type default)
		)
	)
	(wire
		(pts
			(xy 331.47 105.41) (xy 351.79 105.41)
		)
		(stroke
			(width 0)
			(type default)
		)
	)
	(wire
		(pts
			(xy 219.71 86.36) (xy 232.41 86.36)
		)
		(stroke
			(width 0)
			(type default)
		)
	)
	(wire
		(pts
			(xy 54.61 203.2) (xy 105.41 203.2)
		)
		(stroke
			(width 0)
			(type default)
		)
	)
	(wire
		(pts
			(xy 68.58 74.93) (xy 68.58 78.74)
		)
		(stroke
			(width 0)
			(type default)
		)
	)
	(wire
		(pts
			(xy 168.91 45.72) (xy 172.72 45.72)
		)
		(stroke
			(width 0)
			(type default)
		)
	)
	(wire
		(pts
			(xy 151.13 99.06) (xy 175.26 99.06)
		)
		(stroke
			(width 0)
			(type default)
		)
	)
	(wire
		(pts
			(xy 54.61 205.74) (xy 105.41 205.74)
		)
		(stroke
			(width 0)
			(type default)
		)
	)
	(wire
		(pts
			(xy 237.49 43.18) (xy 237.49 44.45)
		)
		(stroke
			(width 0)
			(type default)
		)
	)
	(wire
		(pts
			(xy 25.4 260.35) (xy 52.07 260.35)
		)
		(stroke
			(width 0)
			(type default)
		)
	)
	(wire
		(pts
			(xy 25.4 114.3) (xy 52.07 114.3)
		)
		(stroke
			(width 0)
			(type default)
		)
	)
	(wire
		(pts
			(xy 317.5 35.56) (xy 327.66 35.56)
		)
		(stroke
			(width 0)
			(type default)
		)
	)
	(bus
		(pts
			(xy 318.77 180.34) (xy 318.77 182.88)
		)
		(stroke
			(width 0)
			(type default)
		)
	)
	(wire
		(pts
			(xy 175.26 167.64) (xy 177.8 167.64)
		)
		(stroke
			(width 0)
			(type default)
		)
	)
	(wire
		(pts
			(xy 312.42 157.48) (xy 328.295 157.48)
		)
		(stroke
			(width 0)
			(type default)
		)
	)
	(wire
		(pts
			(xy 153.67 118.11) (xy 153.67 120.65)
		)
		(stroke
			(width 0)
			(type default)
		)
	)
	(wire
		(pts
			(xy 25.4 72.39) (xy 52.07 72.39)
		)
		(stroke
			(width 0)
			(type default)
		)
	)
	(wire
		(pts
			(xy 124.46 120.65) (xy 124.46 124.46)
		)
		(stroke
			(width 0)
			(type default)
		)
	)
	(wire
		(pts
			(xy 327.66 29.21) (xy 327.66 35.56)
		)
		(stroke
			(width 0)
			(type default)
		)
	)
	(wire
		(pts
			(xy 57.15 243.84) (xy 68.58 243.84)
		)
		(stroke
			(width 0)
			(type default)
		)
	)
	(wire
		(pts
			(xy 289.56 208.28) (xy 311.15 208.28)
		)
		(stroke
			(width 0)
			(type default)
		)
	)
	(wire
		(pts
			(xy 151.13 76.2) (xy 175.26 76.2)
		)
		(stroke
			(width 0)
			(type default)
		)
	)
	(wire
		(pts
			(xy 243.84 239.395) (xy 262.89 239.395)
		)
		(stroke
			(width 0)
			(type default)
		)
	)
	(wire
		(pts
			(xy 177.8 167.64) (xy 177.8 154.94)
		)
		(stroke
			(width 0)
			(type default)
		)
	)
	(wire
		(pts
			(xy 190.5 245.11) (xy 190.5 247.65)
		)
		(stroke
			(width 0)
			(type default)
		)
	)
	(wire
		(pts
			(xy 54.61 175.26) (xy 105.41 175.26)
		)
		(stroke
			(width 0)
			(type default)
		)
	)
	(wire
		(pts
			(xy 237.49 19.05) (xy 237.49 21.59)
		)
		(stroke
			(width 0)
			(type default)
		)
	)
	(wire
		(pts
			(xy 152.4 19.05) (xy 172.72 19.05)
		)
		(stroke
			(width 0)
			(type default)
		)
	)
	(wire
		(pts
			(xy 259.08 19.05) (xy 247.65 19.05)
		)
		(stroke
			(width 0)
			(type default)
		)
	)
	(wire
		(pts
			(xy 129.54 229.87) (xy 123.19 229.87)
		)
		(stroke
			(width 0)
			(type default)
		)
	)
	(wire
		(pts
			(xy 52.07 88.9) (xy 25.4 88.9)
		)
		(stroke
			(width 0)
			(type default)
		)
	)
	(bus
		(pts
			(xy 200.66 273.05) (xy 199.39 274.32)
		)
		(stroke
			(width 0)
			(type default)
		)
	)
	(wire
		(pts
			(xy 68.58 52.07) (xy 68.58 55.88)
		)
		(stroke
			(width 0)
			(type default)
		)
	)
	(wire
		(pts
			(xy 317.5 19.05) (xy 290.83 19.05)
		)
		(stroke
			(width 0)
			(type default)
		)
	)
	(wire
		(pts
			(xy 233.68 195.58) (xy 266.7 195.58)
		)
		(stroke
			(width 0)
			(type default)
		)
	)
	(wire
		(pts
			(xy 129.54 238.76) (xy 129.54 241.3)
		)
		(stroke
			(width 0)
			(type default)
		)
	)
	(wire
		(pts
			(xy 52.07 102.87) (xy 25.4 102.87)
		)
		(stroke
			(width 0)
			(type default)
		)
	)
	(wire
		(pts
			(xy 312.42 157.48) (xy 312.42 161.29)
		)
		(stroke
			(width 0)
			(type default)
		)
	)
	(wire
		(pts
			(xy 86.36 187.96) (xy 137.16 187.96)
		)
		(stroke
			(width 0)
			(type default)
		)
	)
	(wire
		(pts
			(xy 120.65 43.18) (xy 120.65 44.45)
		)
		(stroke
			(width 0)
			(type default)
		)
	)
	(wire
		(pts
			(xy 290.83 26.67) (xy 290.83 29.21)
		)
		(stroke
			(width 0)
			(type default)
		)
	)
	(bus
		(pts
			(xy 149.86 100.33) (xy 149.86 105.41)
		)
		(stroke
			(width 0)
			(type default)
		)
	)
	(wire
		(pts
			(xy 347.98 171.45) (xy 379.73 171.45)
		)
		(stroke
			(width 0)
			(type default)
		)
	)
	(wire
		(pts
			(xy 57.15 67.31) (xy 68.58 67.31)
		)
		(stroke
			(width 0)
			(type default)
		)
	)
	(wire
		(pts
			(xy 68.58 96.52) (xy 68.58 100.33)
		)
		(stroke
			(width 0)
			(type default)
		)
	)
	(wire
		(pts
			(xy 142.24 35.56) (xy 142.24 38.1)
		)
		(stroke
			(width 0)
			(type default)
		)
	)
	(wire
		(pts
			(xy 233.68 179.07) (xy 233.68 181.61)
		)
		(stroke
			(width 0)
			(type default)
		)
	)
	(wire
		(pts
			(xy 144.78 129.54) (xy 144.78 132.08)
		)
		(stroke
			(width 0)
			(type default)
		)
	)
	(wire
		(pts
			(xy 290.83 19.05) (xy 280.67 19.05)
		)
		(stroke
			(width 0)
			(type default)
		)
	)
	(wire
		(pts
			(xy 175.26 195.58) (xy 233.68 195.58)
		)
		(stroke
			(width 0)
			(type default)
		)
	)
	(wire
		(pts
			(xy 111.76 55.88) (xy 116.84 55.88)
		)
		(stroke
			(width 0)
			(type default)
		)
	)
	(bus
		(pts
			(xy 149.86 97.79) (xy 149.86 100.33)
		)
		(stroke
			(width 0)
			(type default)
		)
	)
	(wire
		(pts
			(xy 294.64 157.48) (xy 300.99 157.48)
		)
		(stroke
			(width 0)
			(type default)
		)
	)
	(wire
		(pts
			(xy 289.56 233.68) (xy 311.15 233.68)
		)
		(stroke
			(width 0)
			(type default)
		)
	)
	(wire
		(pts
			(xy 406.4 212.09) (xy 406.4 214.63)
		)
		(stroke
			(width 0)
			(type default)
		)
	)
	(wire
		(pts
			(xy 220.98 186.69) (xy 220.98 193.04)
		)
		(stroke
			(width 0)
			(type default)
		)
	)
	(bus
		(pts
			(xy 200.66 273.05) (xy 200.66 269.24)
		)
		(stroke
			(width 0)
			(type default)
		)
	)
	(wire
		(pts
			(xy 220.98 162.56) (xy 220.98 163.83)
		)
		(stroke
			(width 0)
			(type default)
		)
	)
	(wire
		(pts
			(xy 378.46 114.3) (xy 396.24 114.3)
		)
		(stroke
			(width 0)
			(type default)
		)
	)
	(wire
		(pts
			(xy 172.72 45.72) (xy 175.26 45.72)
		)
		(stroke
			(width 0)
			(type default)
		)
	)
	(wire
		(pts
			(xy 378.46 176.53) (xy 379.73 176.53)
		)
		(stroke
			(width 0)
			(type default)
		)
	)
	(wire
		(pts
			(xy 57.15 102.87) (xy 68.58 102.87)
		)
		(stroke
			(width 0)
			(type default)
		)
	)
	(wire
		(pts
			(xy 247.65 35.56) (xy 259.08 35.56)
		)
		(stroke
			(width 0)
			(type default)
		)
	)
	(wire
		(pts
			(xy 177.8 215.9) (xy 177.8 222.25)
		)
		(stroke
			(width 0)
			(type default)
		)
	)
	(wire
		(pts
			(xy 219.71 93.98) (xy 238.76 93.98)
		)
		(stroke
			(width 0)
			(type default)
		)
	)
	(wire
		(pts
			(xy 127 154.94) (xy 135.89 154.94)
		)
		(stroke
			(width 0)
			(type default)
		)
	)
	(bus
		(pts
			(xy 149.86 85.09) (xy 149.86 87.63)
		)
		(stroke
			(width 0)
			(type default)
		)
	)
	(wire
		(pts
			(xy 219.71 114.3) (xy 223.52 114.3)
		)
		(stroke
			(width 0)
			(type default)
		)
	)
	(wire
		(pts
			(xy 57.15 88.9) (xy 68.58 88.9)
		)
		(stroke
			(width 0)
			(type default)
		)
	)
	(wire
		(pts
			(xy 396.24 105.41) (xy 396.24 106.68)
		)
		(stroke
			(width 0)
			(type default)
		)
	)
	(wire
		(pts
			(xy 152.4 35.56) (xy 142.24 35.56)
		)
		(stroke
			(width 0)
			(type default)
		)
	)
	(wire
		(pts
			(xy 246.38 208.28) (xy 246.38 205.74)
		)
		(stroke
			(width 0)
			(type default)
		)
	)
	(wire
		(pts
			(xy 68.58 240.03) (xy 68.58 243.84)
		)
		(stroke
			(width 0)
			(type default)
		)
	)
	(wire
		(pts
			(xy 269.24 19.05) (xy 269.24 21.59)
		)
		(stroke
			(width 0)
			(type default)
		)
	)
	(wire
		(pts
			(xy 151.13 96.52) (xy 175.26 96.52)
		)
		(stroke
			(width 0)
			(type default)
		)
	)
	(wire
		(pts
			(xy 190.5 252.73) (xy 190.5 255.27)
		)
		(stroke
			(width 0)
			(type default)
		)
	)
	(wire
		(pts
			(xy 121.92 220.98) (xy 129.54 220.98)
		)
		(stroke
			(width 0)
			(type default)
		)
	)
	(wire
		(pts
			(xy 114.3 35.56) (xy 120.65 35.56)
		)
		(stroke
			(width 0)
			(type default)
		)
	)
	(bus
		(pts
			(xy 53.34 176.53) (xy 53.34 181.61)
		)
		(stroke
			(width 0)
			(type default)
		)
	)
	(wire
		(pts
			(xy 261.62 179.07) (xy 261.62 180.34)
		)
		(stroke
			(width 0)
			(type default)
		)
	)
	(wire
		(pts
			(xy 220.98 154.94) (xy 232.41 154.94)
		)
		(stroke
			(width 0)
			(type default)
		)
	)
	(wire
		(pts
			(xy 57.15 114.3) (xy 68.58 114.3)
		)
		(stroke
			(width 0)
			(type default)
		)
	)
	(wire
		(pts
			(xy 396.24 99.695) (xy 396.24 97.79)
		)
		(stroke
			(width 0)
			(type default)
		)
	)
	(polyline
		(pts
			(xy 279.4 284.48) (xy 279.4 146.05)
		)
		(stroke
			(width 0)
			(type default)
		)
	)
	(polyline
		(pts
			(xy 82.55 44.45) (xy 82.55 133.35)
		)
		(stroke
			(width 0)
			(type solid)
		)
	)
	(wire
		(pts
			(xy 153.67 120.65) (xy 162.56 120.65)
		)
		(stroke
			(width 0)
			(type default)
		)
	)
	(wire
		(pts
			(xy 208.28 179.07) (xy 208.28 181.61)
		)
		(stroke
			(width 0)
			(type default)
		)
	)
	(bus
		(pts
			(xy 309.88 187.96) (xy 317.5 187.96)
		)
		(stroke
			(width 0)
			(type default)
		)
	)
	(wire
		(pts
			(xy 57.15 229.87) (xy 68.58 229.87)
		)
		(stroke
			(width 0)
			(type default)
		)
	)
	(wire
		(pts
			(xy 237.49 35.56) (xy 247.65 35.56)
		)
		(stroke
			(width 0)
			(type default)
		)
	)
	(polyline
		(pts
			(xy 285.75 198.12) (xy 345.44 198.12)
		)
		(stroke
			(width 0)
			(type default)
		)
	)
	(wire
		(pts
			(xy 57.15 111.76) (xy 68.58 111.76)
		)
		(stroke
			(width 0)
			(type default)
		)
	)
	(wire
		(pts
			(xy 68.58 60.96) (xy 68.58 63.5)
		)
		(stroke
			(width 0)
			(type default)
		)
	)
	(wire
		(pts
			(xy 220.98 193.04) (xy 266.7 193.04)
		)
		(stroke
			(width 0)
			(type default)
		)
	)
	(wire
		(pts
			(xy 243.84 243.84) (xy 259.08 243.84)
		)
		(stroke
			(width 0)
			(type default)
		)
	)
	(wire
		(pts
			(xy 289.56 236.22) (xy 311.15 236.22)
		)
		(stroke
			(width 0)
			(type default)
		)
	)
	(wire
		(pts
			(xy 220.98 154.94) (xy 220.98 157.48)
		)
		(stroke
			(width 0)
			(type default)
		)
	)
	(wire
		(pts
			(xy 327.66 19.05) (xy 327.66 24.13)
		)
		(stroke
			(width 0)
			(type default)
		)
	)
	(wire
		(pts
			(xy 406.4 209.55) (xy 406.4 212.09)
		)
		(stroke
			(width 0)
			(type default)
		)
	)
	(wire
		(pts
			(xy 25.4 105.41) (xy 52.07 105.41)
		)
		(stroke
			(width 0)
			(type default)
		)
	)
	(wire
		(pts
			(xy 175.26 198.12) (xy 246.38 198.12)
		)
		(stroke
			(width 0)
			(type default)
		)
	)
	(wire
		(pts
			(xy 377.19 176.53) (xy 377.19 181.61)
		)
		(stroke
			(width 0)
			(type default)
		)
	)
	(wire
		(pts
			(xy 331.47 97.79) (xy 351.79 97.79)
		)
		(stroke
			(width 0)
			(type default)
		)
	)
	(wire
		(pts
			(xy 325.12 123.19) (xy 325.12 125.73)
		)
		(stroke
			(width 0)
			(type default)
		)
	)
	(wire
		(pts
			(xy 25.4 91.44) (xy 52.07 91.44)
		)
		(stroke
			(width 0)
			(type default)
		)
	)
	(wire
		(pts
			(xy 144.78 120.65) (xy 153.67 120.65)
		)
		(stroke
			(width 0)
			(type default)
		)
	)
	(wire
		(pts
			(xy 110.49 175.26) (xy 137.16 175.26)
		)
		(stroke
			(width 0)
			(type default)
		)
	)
	(wire
		(pts
			(xy 289.56 228.6) (xy 311.15 228.6)
		)
		(stroke
			(width 0)
			(type default)
		)
	)
	(polyline
		(pts
			(xy 265.43 57.15) (xy 265.43 34.29)
		)
		(stroke
			(width 0)
			(type default)
		)
	)
	(wire
		(pts
			(xy 130.81 43.18) (xy 130.81 44.45)
		)
		(stroke
			(width 0)
			(type default)
		)
	)
	(bus
		(pts
			(xy 149.86 67.31) (xy 149.86 72.39)
		)
		(stroke
			(width 0)
			(type default)
		)
	)
	(wire
		(pts
			(xy 184.15 154.94) (xy 184.15 157.48)
		)
		(stroke
			(width 0)
			(type default)
		)
	)
	(wire
		(pts
			(xy 151.13 63.5) (xy 175.26 63.5)
		)
		(stroke
			(width 0)
			(type default)
		)
	)
	(wire
		(pts
			(xy 25.4 267.97) (xy 52.07 267.97)
		)
		(stroke
			(width 0)
			(type default)
		)
	)
	(wire
		(pts
			(xy 57.15 74.93) (xy 68.58 74.93)
		)
		(stroke
			(width 0)
			(type default)
		)
	)
	(wire
		(pts
			(xy 261.62 265.43) (xy 261.62 267.97)
		)
		(stroke
			(width 0)
			(type default)
		)
	)
	(wire
		(pts
			(xy 347.98 179.07) (xy 375.92 179.07)
		)
		(stroke
			(width 0)
			(type default)
		)
	)
	(wire
		(pts
			(xy 25.4 100.33) (xy 52.07 100.33)
		)
		(stroke
			(width 0)
			(type default)
		)
	)
	(wire
		(pts
			(xy 177.8 170.18) (xy 177.8 167.64)
		)
		(stroke
			(width 0)
			(type default)
		)
	)
	(wire
		(pts
			(xy 347.98 157.48) (xy 354.33 157.48)
		)
		(stroke
			(width 0)
			(type default)
		)
	)
	(bus
		(pts
			(xy 335.28 133.35) (xy 335.28 129.54)
		)
		(stroke
			(width 0)
			(type default)
		)
	)
	(wire
		(pts
			(xy 52.07 172.72) (xy 30.48 172.72)
		)
		(stroke
			(width 0)
			(type default)
		)
	)
	(wire
		(pts
			(xy 320.04 168.91) (xy 342.9 168.91)
		)
		(stroke
			(width 0)
			(type default)
		)
	)
	(wire
		(pts
			(xy 269.24 35.56) (xy 280.67 35.56)
		)
		(stroke
			(width 0)
			(type default)
		)
	)
	(wire
		(pts
			(xy 119.38 234.95) (xy 119.38 241.3)
		)
		(stroke
			(width 0)
			(type default)
		)
	)
	(wire
		(pts
			(xy 142.24 26.67) (xy 142.24 29.21)
		)
		(stroke
			(width 0)
			(type default)
		)
	)
	(wire
		(pts
			(xy 130.81 19.05) (xy 130.81 21.59)
		)
		(stroke
			(width 0)
			(type default)
		)
	)
	(wire
		(pts
			(xy 152.4 43.18) (xy 152.4 44.45)
		)
		(stroke
			(width 0)
			(type default)
		)
	)
	(wire
		(pts
			(xy 208.28 186.69) (xy 208.28 190.5)
		)
		(stroke
			(width 0)
			(type default)
		)
	)
	(wire
		(pts
			(xy 378.46 128.27) (xy 379.73 128.27)
		)
		(stroke
			(width 0)
			(type default)
		)
	)
	(polyline
		(pts
			(xy 285.75 198.12) (xy 285.75 250.19)
		)
		(stroke
			(width 0)
			(type default)
		)
	)
	(polyline
		(pts
			(xy 269.24 214.63) (xy 269.24 173.99)
		)
		(stroke
			(width 0)
			(type default)
		)
	)
	(wire
		(pts
			(xy 195.58 154.94) (xy 195.58 157.48)
		)
		(stroke
			(width 0)
			(type default)
		)
	)
	(wire
		(pts
			(xy 151.13 55.88) (xy 175.26 55.88)
		)
		(stroke
			(width 0)
			(type default)
		)
	)
	(wire
		(pts
			(xy 57.15 264.16) (xy 68.58 264.16)
		)
		(stroke
			(width 0)
			(type default)
		)
	)
	(bus
		(pts
			(xy 149.86 77.47) (xy 149.86 80.01)
		)
		(stroke
			(width 0)
			(type default)
		)
	)
	(wire
		(pts
			(xy 68.58 58.42) (xy 68.58 60.96)
		)
		(stroke
			(width 0)
			(type default)
		)
	)
	(wire
		(pts
			(xy 190.5 255.27) (xy 217.17 255.27)
		)
		(stroke
			(width 0)
			(type default)
		)
	)
	(wire
		(pts
			(xy 248.92 154.94) (xy 247.65 154.94)
		)
		(stroke
			(width 0)
			(type default)
		)
	)
	(wire
		(pts
			(xy 203.2 179.07) (xy 208.28 179.07)
		)
		(stroke
			(width 0)
			(type default)
		)
	)
	(wire
		(pts
			(xy 144.78 120.65) (xy 138.43 120.65)
		)
		(stroke
			(width 0)
			(type default)
		)
	)
	(wire
		(pts
			(xy 68.58 227.33) (xy 68.58 229.87)
		)
		(stroke
			(width 0)
			(type default)
		)
	)
	(wire
		(pts
			(xy 25.4 256.54) (xy 52.07 256.54)
		)
		(stroke
			(width 0)
			(type default)
		)
	)
	(wire
		(pts
			(xy 129.54 229.87) (xy 129.54 220.98)
		)
		(stroke
			(width 0)
			(type default)
		)
	)
	(wire
		(pts
			(xy 246.38 198.12) (xy 246.38 200.66)
		)
		(stroke
			(width 0)
			(type default)
		)
	)
	(wire
		(pts
			(xy 68.58 72.39) (xy 68.58 74.93)
		)
		(stroke
			(width 0)
			(type default)
		)
	)
	(wire
		(pts
			(xy 110.49 154.94) (xy 116.84 154.94)
		)
		(stroke
			(width 0)
			(type default)
		)
	)
	(wire
		(pts
			(xy 25.4 96.52) (xy 52.07 96.52)
		)
		(stroke
			(width 0)
			(type default)
		)
	)
	(wire
		(pts
			(xy 223.52 19.05) (xy 223.52 38.1)
		)
		(stroke
			(width 0)
			(type default)
		)
	)
	(wire
		(pts
			(xy 130.81 35.56) (xy 130.81 38.1)
		)
		(stroke
			(width 0)
			(type default)
		)
	)
	(polyline
		(pts
			(xy 233.68 34.29) (xy 233.68 57.15)
		)
		(stroke
			(width 0)
			(type default)
		)
	)
	(wire
		(pts
			(xy 246.38 179.07) (xy 254 179.07)
		)
		(stroke
			(width 0)
			(type default)
		)
	)
	(wire
		(pts
			(xy 106.68 229.87) (xy 115.57 229.87)
		)
		(stroke
			(width 0)
			(type default)
		)
	)
	(bus
		(pts
			(xy 331.47 134.62) (xy 334.01 134.62)
		)
		(stroke
			(width 0)
			(type default)
		)
	)
	(wire
		(pts
			(xy 328.295 157.48) (xy 342.9 157.48)
		)
		(stroke
			(width 0)
			(type default)
		)
	)
	(wire
		(pts
			(xy 57.15 60.96) (xy 68.58 60.96)
		)
		(stroke
			(width 0)
			(type default)
		)
	)
	(polyline
		(pts
			(xy 19.05 280.67) (xy 19.05 215.9)
		)
		(stroke
			(width 0)
			(type solid)
		)
	)
	(wire
		(pts
			(xy 331.47 107.95) (xy 351.79 107.95)
		)
		(stroke
			(width 0)
			(type default)
		)
	)
	(wire
		(pts
			(xy 259.08 19.05) (xy 259.08 21.59)
		)
		(stroke
			(width 0)
			(type default)
		)
	)
	(wire
		(pts
			(xy 190.5 255.27) (xy 190.5 257.81)
		)
		(stroke
			(width 0)
			(type default)
		)
	)
	(bus
		(pts
			(xy 53.34 173.99) (xy 53.34 176.53)
		)
		(stroke
			(width 0)
			(type default)
		)
	)
	(wire
		(pts
			(xy 289.56 210.82) (xy 311.15 210.82)
		)
		(stroke
			(width 0)
			(type default)
		)
	)
	(bus
		(pts
			(xy 149.86 72.39) (xy 149.86 74.93)
		)
		(stroke
			(width 0)
			(type default)
		)
	)
	(wire
		(pts
			(xy 243.84 249.555) (xy 259.08 249.555)
		)
		(stroke
			(width 0)
			(type default)
		)
	)
	(polyline
		(pts
			(xy 349.25 113.03) (xy 349.25 85.09)
		)
		(stroke
			(width 0)
			(type default)
		)
	)
	(wire
		(pts
			(xy 309.88 213.36) (xy 309.88 214.63)
		)
		(stroke
			(width 0)
			(type default)
		)
	)
	(wire
		(pts
			(xy 184.15 213.36) (xy 184.15 215.9)
		)
		(stroke
			(width 0)
			(type default)
		)
	)
	(wire
		(pts
			(xy 142.24 43.18) (xy 142.24 44.45)
		)
		(stroke
			(width 0)
			(type default)
		)
	)
	(wire
		(pts
			(xy 68.58 114.3) (xy 68.58 111.76)
		)
		(stroke
			(width 0)
			(type default)
		)
	)
	(wire
		(pts
			(xy 379.73 189.23) (xy 374.65 189.23)
		)
		(stroke
			(width 0)
			(type default)
		)
	)
	(wire
		(pts
			(xy 262.89 254) (xy 262.89 252.73)
		)
		(stroke
			(width 0)
			(type default)
		)
	)
	(wire
		(pts
			(xy 116.84 162.56) (xy 116.84 163.83)
		)
		(stroke
			(width 0)
			(type default)
		)
	)
	(wire
		(pts
			(xy 57.15 63.5) (xy 68.58 63.5)
		)
		(stroke
			(width 0)
			(type default)
		)
	)
	(wire
		(pts
			(xy 106.68 229.87) (xy 106.68 233.68)
		)
		(stroke
			(width 0)
			(type default)
		)
	)
	(wire
		(pts
			(xy 120.65 19.05) (xy 120.65 21.59)
		)
		(stroke
			(width 0)
			(type default)
		)
	)
	(wire
		(pts
			(xy 54.61 190.5) (xy 81.28 190.5)
		)
		(stroke
			(width 0)
			(type default)
		)
	)
	(wire
		(pts
			(xy 52.07 111.76) (xy 25.4 111.76)
		)
		(stroke
			(width 0)
			(type default)
		)
	)
	(wire
		(pts
			(xy 25.4 69.85) (xy 52.07 69.85)
		)
		(stroke
			(width 0)
			(type default)
		)
	)
	(wire
		(pts
			(xy 233.68 208.28) (xy 233.68 205.74)
		)
		(stroke
			(width 0)
			(type default)
		)
	)
	(wire
		(pts
			(xy 223.52 40.64) (xy 219.71 40.64)
		)
		(stroke
			(width 0)
			(type default)
		)
	)
	(wire
		(pts
			(xy 219.71 83.82) (xy 232.41 83.82)
		)
		(stroke
			(width 0)
			(type default)
		)
	)
	(wire
		(pts
			(xy 311.15 213.36) (xy 309.88 213.36)
		)
		(stroke
			(width 0)
			(type default)
		)
	)
	(wire
		(pts
			(xy 237.49 154.94) (xy 247.65 154.94)
		)
		(stroke
			(width 0)
			(type default)
		)
	)
	(polyline
		(pts
			(xy 233.68 57.15) (xy 265.43 57.15)
		)
		(stroke
			(width 0)
			(type default)
		)
	)
	(wire
		(pts
			(xy 25.4 236.22) (xy 52.07 236.22)
		)
		(stroke
			(width 0)
			(type default)
		)
	)
	(polyline
		(pts
			(xy 205.74 173.99) (xy 205.74 214.63)
		)
		(stroke
			(width 0)
			(type default)
		)
	)
	(wire
		(pts
			(xy 68.58 93.98) (xy 68.58 96.52)
		)
		(stroke
			(width 0)
			(type default)
		)
	)
	(wire
		(pts
			(xy 151.13 93.98) (xy 175.26 93.98)
		)
		(stroke
			(width 0)
			(type default)
		)
	)
	(wire
		(pts
			(xy 57.15 91.44) (xy 68.58 91.44)
		)
		(stroke
			(width 0)
			(type default)
		)
	)
	(wire
		(pts
			(xy 137.16 213.36) (xy 106.68 213.36)
		)
		(stroke
			(width 0)
			(type default)
		)
	)
	(bus
		(pts
			(xy 149.86 74.93) (xy 149.86 77.47)
		)
		(stroke
			(width 0)
			(type default)
		)
	)
	(wire
		(pts
			(xy 130.81 26.67) (xy 130.81 29.21)
		)
		(stroke
			(width 0)
			(type default)
		)
	)
	(wire
		(pts
			(xy 243.84 254) (xy 262.89 254)
		)
		(stroke
			(width 0)
			(type default)
		)
	)
	(wire
		(pts
			(xy 54.61 198.12) (xy 105.41 198.12)
		)
		(stroke
			(width 0)
			(type default)
		)
	)
	(polyline
		(pts
			(xy 96.52 212.09) (xy 96.52 171.45)
		)
		(stroke
			(width 0)
			(type default)
		)
	)
	(wire
		(pts
			(xy 25.4 81.28) (xy 52.07 81.28)
		)
		(stroke
			(width 0)
			(type default)
		)
	)
	(wire
		(pts
			(xy 114.3 29.21) (xy 114.3 35.56)
		)
		(stroke
			(width 0)
			(type default)
		)
	)
	(wire
		(pts
			(xy 347.98 176.53) (xy 377.19 176.53)
		)
		(stroke
			(width 0)
			(type default)
		)
	)
	(polyline
		(pts
			(xy 345.44 198.12) (xy 345.44 250.19)
		)
		(stroke
			(width 0)
			(type default)
		)
	)
	(wire
		(pts
			(xy 68.58 251.46) (xy 68.58 254)
		)
		(stroke
			(width 0)
			(type default)
		)
	)
	(wire
		(pts
			(xy 172.72 38.1) (xy 172.72 19.05)
		)
		(stroke
			(width 0)
			(type default)
		)
	)
	(wire
		(pts
			(xy 68.58 223.52) (xy 68.58 227.33)
		)
		(stroke
			(width 0)
			(type default)
		)
	)
	(wire
		(pts
			(xy 406.4 204.47) (xy 406.4 207.01)
		)
		(stroke
			(width 0)
			(type default)
		)
	)
	(wire
		(pts
			(xy 151.13 66.04) (xy 175.26 66.04)
		)
		(stroke
			(width 0)
			(type default)
		)
	)
	(wire
		(pts
			(xy 220.98 208.28) (xy 220.98 205.74)
		)
		(stroke
			(width 0)
			(type default)
		)
	)
	(wire
		(pts
			(xy 184.15 172.72) (xy 184.15 175.26)
		)
		(stroke
			(width 0)
			(type default)
		)
	)
	(wire
		(pts
			(xy 195.58 180.34) (xy 195.58 182.88)
		)
		(stroke
			(width 0)
			(type default)
		)
	)
	(wire
		(pts
			(xy 201.93 262.89) (xy 217.17 262.89)
		)
		(stroke
			(width 0)
			(type default)
		)
	)
	(wire
		(pts
			(xy 208.28 179.07) (xy 220.98 179.07)
		)
		(stroke
			(width 0)
			(type default)
		)
	)
	(wire
		(pts
			(xy 57.15 227.33) (xy 68.58 227.33)
		)
		(stroke
			(width 0)
			(type default)
		)
	)
	(wire
		(pts
			(xy 219.71 48.26) (xy 227.33 48.26)
		)
		(stroke
			(width 0)
			(type default)
		)
	)
	(wire
		(pts
			(xy 259.08 35.56) (xy 269.24 35.56)
		)
		(stroke
			(width 0)
			(type default)
		)
	)
	(wire
		(pts
			(xy 54.61 172.72) (xy 137.16 172.72)
		)
		(stroke
			(width 0)
			(type default)
		)
	)
	(wire
		(pts
			(xy 219.71 63.5) (xy 232.41 63.5)
		)
		(stroke
			(width 0)
			(type default)
		)
	)
	(wire
		(pts
			(xy 137.16 167.64) (xy 135.89 167.64)
		)
		(stroke
			(width 0)
			(type default)
		)
	)
	(wire
		(pts
			(xy 142.24 19.05) (xy 142.24 21.59)
		)
		(stroke
			(width 0)
			(type default)
		)
	)
	(wire
		(pts
			(xy 116.84 154.94) (xy 127 154.94)
		)
		(stroke
			(width 0)
			(type default)
		)
	)
	(wire
		(pts
			(xy 184.15 220.98) (xy 184.15 222.25)
		)
		(stroke
			(width 0)
			(type default)
		)
	)
	(wire
		(pts
			(xy 151.13 88.9) (xy 175.26 88.9)
		)
		(stroke
			(width 0)
			(type default)
		)
	)
	(wire
		(pts
			(xy 177.8 154.94) (xy 184.15 154.94)
		)
		(stroke
			(width 0)
			(type default)
		)
	)
	(wire
		(pts
			(xy 317.5 26.67) (xy 317.5 29.21)
		)
		(stroke
			(width 0)
			(type default)
		)
	)
	(wire
		(pts
			(xy 151.13 73.66) (xy 175.26 73.66)
		)
		(stroke
			(width 0)
			(type default)
		)
	)
	(wire
		(pts
			(xy 168.91 35.56) (xy 168.91 45.72)
		)
		(stroke
			(width 0)
			(type default)
		)
	)
	(wire
		(pts
			(xy 153.67 111.76) (xy 175.26 111.76)
		)
		(stroke
			(width 0)
			(type default)
		)
	)
	(polyline
		(pts
			(xy 323.85 113.03) (xy 349.25 113.03)
		)
		(stroke
			(width 0)
			(type default)
		)
	)
	(wire
		(pts
			(xy 233.68 179.07) (xy 246.38 179.07)
		)
		(stroke
			(width 0)
			(type default)
		)
	)
	(wire
		(pts
			(xy 68.58 254) (xy 68.58 256.54)
		)
		(stroke
			(width 0)
			(type default)
		)
	)
	(wire
		(pts
			(xy 57.15 93.98) (xy 68.58 93.98)
		)
		(stroke
			(width 0)
			(type default)
		)
	)
	(wire
		(pts
			(xy 379.73 191.77) (xy 373.38 191.77)
		)
		(stroke
			(width 0)
			(type default)
		)
	)
	(wire
		(pts
			(xy 220.98 179.07) (xy 233.68 179.07)
		)
		(stroke
			(width 0)
			(type default)
		)
	)
	(wire
		(pts
			(xy 195.58 172.72) (xy 195.58 175.26)
		)
		(stroke
			(width 0)
			(type default)
		)
	)
	(wire
		(pts
			(xy 121.92 55.88) (xy 148.59 55.88)
		)
		(stroke
			(width 0)
			(type default)
		)
	)
	(wire
		(pts
			(xy 247.65 162.56) (xy 247.65 163.83)
		)
		(stroke
			(width 0)
			(type default)
		)
	)
	(polyline
		(pts
			(xy 82.55 280.67) (xy 19.05 280.67)
		)
		(stroke
			(width 0)
			(type solid)
		)
	)
	(bus
		(pts
			(xy 149.86 80.01) (xy 149.86 82.55)
		)
		(stroke
			(width 0)
			(type default)
		)
	)
	(wire
		(pts
			(xy 378.46 173.99) (xy 378.46 176.53)
		)
		(stroke
			(width 0)
			(type default)
		)
	)
	(wire
		(pts
			(xy 233.68 186.69) (xy 233.68 195.58)
		)
		(stroke
			(width 0)
			(type default)
		)
	)
	(bus
		(pts
			(xy 200.66 264.16) (xy 200.66 261.62)
		)
		(stroke
			(width 0)
			(type default)
		)
	)
	(bus
		(pts
			(xy 53.34 199.39) (xy 53.34 201.93)
		)
		(stroke
			(width 0)
			(type default)
		)
	)
	(bus
		(pts
			(xy 53.34 191.77) (xy 53.34 194.31)
		)
		(stroke
			(width 0)
			(type default)
		)
	)
	(wire
		(pts
			(xy 57.15 251.46) (xy 68.58 251.46)
		)
		(stroke
			(width 0)
			(type default)
		)
	)
	(wire
		(pts
			(xy 331.47 100.33) (xy 351.79 100.33)
		)
		(stroke
			(width 0)
			(type default)
		)
	)
	(wire
		(pts
			(xy 261.62 273.05) (xy 261.62 275.59)
		)
		(stroke
			(width 0)
			(type default)
		)
	)
	(wire
		(pts
			(xy 219.71 60.96) (xy 232.41 60.96)
		)
		(stroke
			(width 0)
			(type default)
		)
	)
	(wire
		(pts
			(xy 219.71 78.74) (xy 232.41 78.74)
		)
		(stroke
			(width 0)
			(type default)
		)
	)
	(polyline
		(pts
			(xy 273.05 146.05) (xy 12.7 146.05)
		)
		(stroke
			(width 0)
			(type default)
		)
	)
	(wire
		(pts
			(xy 25.4 232.41) (xy 52.07 232.41)
		)
		(stroke
			(width 0)
			(type default)
		)
	)
	(bus
		(pts
			(xy 149.86 57.15) (xy 149.86 59.69)
		)
		(stroke
			(width 0)
			(type default)
		)
	)
	(wire
		(pts
			(xy 311.15 238.76) (xy 309.88 238.76)
		)
		(stroke
			(width 0)
			(type default)
		)
	)
	(wire
		(pts
			(xy 378.46 104.14) (xy 393.7 104.14)
		)
		(stroke
			(width 0)
			(type default)
		)
	)
	(bus
		(pts
			(xy 149.86 90.17) (xy 149.86 92.71)
		)
		(stroke
			(width 0)
			(type default)
		)
	)
	(wire
		(pts
			(xy 317.5 43.18) (xy 317.5 44.45)
		)
		(stroke
			(width 0)
			(type default)
		)
	)
	(wire
		(pts
			(xy 86.36 193.04) (xy 137.16 193.04)
		)
		(stroke
			(width 0)
			(type default)
		)
	)
	(bus
		(pts
			(xy 318.77 175.26) (xy 318.77 177.8)
		)
		(stroke
			(width 0)
			(type default)
		)
	)
	(wire
		(pts
			(xy 175.26 190.5) (xy 208.28 190.5)
		)
		(stroke
			(width 0)
			(type default)
		)
	)
	(wire
		(pts
			(xy 57.15 236.22) (xy 68.58 236.22)
		)
		(stroke
			(width 0)
			(type default)
		)
	)
	(wire
		(pts
			(xy 325.12 115.57) (xy 351.79 115.57)
		)
		(stroke
			(width 0)
			(type default)
		)
	)
	(wire
		(pts
			(xy 325.12 115.57) (xy 325.12 118.11)
		)
		(stroke
			(width 0)
			(type default)
		)
	)
	(wire
		(pts
			(xy 175.26 48.26) (xy 172.72 48.26)
		)
		(stroke
			(width 0)
			(type default)
		)
	)
	(wire
		(pts
			(xy 175.26 38.1) (xy 172.72 38.1)
		)
		(stroke
			(width 0)
			(type default)
		)
	)
	(wire
		(pts
			(xy 219.71 38.1) (xy 223.52 38.1)
		)
		(stroke
			(width 0)
			(type default)
		)
	)
	(wire
		(pts
			(xy 151.13 71.12) (xy 175.26 71.12)
		)
		(stroke
			(width 0)
			(type default)
		)
	)
	(wire
		(pts
			(xy 57.15 100.33) (xy 68.58 100.33)
		)
		(stroke
			(width 0)
			(type default)
		)
	)
	(wire
		(pts
			(xy 309.88 238.76) (xy 309.88 240.03)
		)
		(stroke
			(width 0)
			(type default)
		)
	)
	(wire
		(pts
			(xy 25.4 67.31) (xy 52.07 67.31)
		)
		(stroke
			(width 0)
			(type default)
		)
	)
	(wire
		(pts
			(xy 336.55 125.73) (xy 351.79 125.73)
		)
		(stroke
			(width 0)
			(type default)
		)
	)
	(wire
		(pts
			(xy 151.13 81.28) (xy 175.26 81.28)
		)
		(stroke
			(width 0)
			(type default)
		)
	)
	(wire
		(pts
			(xy 162.56 114.3) (xy 162.56 120.65)
		)
		(stroke
			(width 0)
			(type default)
		)
	)
	(wire
		(pts
			(xy 151.13 101.6) (xy 175.26 101.6)
		)
		(stroke
			(width 0)
			(type default)
		)
	)
	(wire
		(pts
			(xy 68.58 236.22) (xy 68.58 240.03)
		)
		(stroke
			(width 0)
			(type default)
		)
	)
	(wire
		(pts
			(xy 151.13 91.44) (xy 175.26 91.44)
		)
		(stroke
			(width 0)
			(type default)
		)
	)
	(bus
		(pts
			(xy 335.28 133.35) (xy 334.01 134.62)
		)
		(stroke
			(width 0)
			(type default)
		)
	)
	(wire
		(pts
			(xy 181.61 245.11) (xy 190.5 245.11)
		)
		(stroke
			(width 0)
			(type default)
		)
	)
	(wire
		(pts
			(xy 152.4 35.56) (xy 152.4 38.1)
		)
		(stroke
			(width 0)
			(type default)
		)
	)
	(wire
		(pts
			(xy 172.72 48.26) (xy 172.72 45.72)
		)
		(stroke
			(width 0)
			(type default)
		)
	)
	(wire
		(pts
			(xy 151.13 106.68) (xy 175.26 106.68)
		)
		(stroke
			(width 0)
			(type default)
		)
	)
	(wire
		(pts
			(xy 269.24 26.67) (xy 269.24 29.21)
		)
		(stroke
			(width 0)
			(type default)
		)
	)
	(wire
		(pts
			(xy 201.93 265.43) (xy 217.17 265.43)
		)
		(stroke
			(width 0)
			(type default)
		)
	)
	(wire
		(pts
			(xy 21.59 172.72) (xy 21.59 180.34)
		)
		(stroke
			(width 0)
			(type default)
		)
	)
	(wire
		(pts
			(xy 121.92 66.04) (xy 148.59 66.04)
		)
		(stroke
			(width 0)
			(type default)
		)
	)
	(wire
		(pts
			(xy 21.59 171.45) (xy 21.59 172.72)
		)
		(stroke
			(width 0)
			(type default)
		)
	)
	(wire
		(pts
			(xy 25.4 180.34) (xy 21.59 180.34)
		)
		(stroke
			(width 0)
			(type default)
		)
	)
	(wire
		(pts
			(xy 195.58 172.72) (xy 184.15 172.72)
		)
		(stroke
			(width 0)
			(type default)
		)
	)
	(wire
		(pts
			(xy 208.28 208.28) (xy 208.28 205.74)
		)
		(stroke
			(width 0)
			(type default)
		)
	)
	(wire
		(pts
			(xy 110.49 203.2) (xy 137.16 203.2)
		)
		(stroke
			(width 0)
			(type default)
		)
	)
	(wire
		(pts
			(xy 68.58 67.31) (xy 68.58 69.85)
		)
		(stroke
			(width 0)
			(type default)
		)
	)
	(wire
		(pts
			(xy 68.58 91.44) (xy 68.58 93.98)
		)
		(stroke
			(width 0)
			(type default)
		)
	)
	(wire
		(pts
			(xy 68.58 88.9) (xy 68.58 91.44)
		)
		(stroke
			(width 0)
			(type default)
		)
	)
	(wire
		(pts
			(xy 25.4 107.95) (xy 52.07 107.95)
		)
		(stroke
			(width 0)
			(type default)
		)
	)
	(polyline
		(pts
			(xy 73.66 212.09) (xy 95.25 212.09)
		)
		(stroke
			(width 0)
			(type default)
		)
	)
	(wire
		(pts
			(xy 52.07 78.74) (xy 25.4 78.74)
		)
		(stroke
			(width 0)
			(type default)
		)
	)
	(wire
		(pts
			(xy 259.08 43.18) (xy 259.08 44.45)
		)
		(stroke
			(width 0)
			(type default)
		)
	)
	(bus
		(pts
			(xy 318.77 167.64) (xy 318.77 170.18)
		)
		(stroke
			(width 0)
			(type default)
		)
	)
	(wire
		(pts
			(xy 153.67 111.76) (xy 153.67 113.03)
		)
		(stroke
			(width 0)
			(type default)
		)
	)
	(wire
		(pts
			(xy 250.19 265.43) (xy 250.19 267.97)
		)
		(stroke
			(width 0)
			(type default)
		)
	)
	(wire
		(pts
			(xy 331.47 113.03) (xy 351.79 113.03)
		)
		(stroke
			(width 0)
			(type default)
		)
	)
	(wire
		(pts
			(xy 111.76 53.34) (xy 111.76 55.88)
		)
		(stroke
			(width 0)
			(type default)
		)
	)
	(bus
		(pts
			(xy 335.28 129.54) (xy 335.28 127)
		)
		(stroke
			(width 0)
			(type default)
		)
	)
	(wire
		(pts
			(xy 405.13 204.47) (xy 406.4 204.47)
		)
		(stroke
			(width 0)
			(type default)
		)
	)
	(wire
		(pts
			(xy 124.46 111.76) (xy 124.46 120.65)
		)
		(stroke
			(width 0)
			(type default)
		)
	)
	(wire
		(pts
			(xy 280.67 35.56) (xy 280.67 38.1)
		)
		(stroke
			(width 0)
			(type default)
		)
	)
	(wire
		(pts
			(xy 201.93 267.97) (xy 217.17 267.97)
		)
		(stroke
			(width 0)
			(type default)
		)
	)
	(bus
		(pts
			(xy 318.77 182.88) (xy 318.77 185.42)
		)
		(stroke
			(width 0)
			(type default)
		)
	)
	(wire
		(pts
			(xy 259.08 26.67) (xy 259.08 29.21)
		)
		(stroke
			(width 0)
			(type default)
		)
	)
	(wire
		(pts
			(xy 68.58 81.28) (xy 68.58 78.74)
		)
		(stroke
			(width 0)
			(type default)
		)
	)
	(wire
		(pts
			(xy 280.67 19.05) (xy 269.24 19.05)
		)
		(stroke
			(width 0)
			(type default)
		)
	)
	(wire
		(pts
			(xy 25.4 251.46) (xy 52.07 251.46)
		)
		(stroke
			(width 0)
			(type default)
		)
	)
	(wire
		(pts
			(xy 320.04 179.07) (xy 342.9 179.07)
		)
		(stroke
			(width 0)
			(type default)
		)
	)
	(wire
		(pts
			(xy 52.07 58.42) (xy 25.4 58.42)
		)
		(stroke
			(width 0)
			(type default)
		)
	)
	(wire
		(pts
			(xy 68.58 55.88) (xy 68.58 58.42)
		)
		(stroke
			(width 0)
			(type default)
		)
	)
	(wire
		(pts
			(xy 110.49 205.74) (xy 137.16 205.74)
		)
		(stroke
			(width 0)
			(type default)
		)
	)
	(wire
		(pts
			(xy 25.4 240.03) (xy 52.07 240.03)
		)
		(stroke
			(width 0)
			(type default)
		)
	)
	(wire
		(pts
			(xy 68.58 232.41) (xy 68.58 236.22)
		)
		(stroke
			(width 0)
			(type default)
		)
	)
	(polyline
		(pts
			(xy 95.25 184.15) (xy 95.25 212.09)
		)
		(stroke
			(width 0)
			(type default)
		)
	)
	(wire
		(pts
			(xy 220.98 179.07) (xy 220.98 181.61)
		)
		(stroke
			(width 0)
			(type default)
		)
	)
	(wire
		(pts
			(xy 25.4 264.16) (xy 52.07 264.16)
		)
		(stroke
			(width 0)
			(type default)
		)
	)
	(wire
		(pts
			(xy 52.07 229.87) (xy 25.4 229.87)
		)
		(stroke
			(width 0)
			(type default)
		)
	)
	(wire
		(pts
			(xy 120.65 19.05) (xy 130.81 19.05)
		)
		(stroke
			(width 0)
			(type default)
		)
	)
	(wire
		(pts
			(xy 124.46 111.76) (xy 153.67 111.76)
		)
		(stroke
			(width 0)
			(type default)
		)
	)
	(wire
		(pts
			(xy 374.65 189.23) (xy 374.65 181.61)
		)
		(stroke
			(width 0)
			(type default)
		)
	)
	(wire
		(pts
			(xy 223.52 111.76) (xy 223.52 114.3)
		)
		(stroke
			(width 0)
			(type default)
		)
	)
	(wire
		(pts
			(xy 68.58 105.41) (xy 68.58 107.95)
		)
		(stroke
			(width 0)
			(type default)
		)
	)
	(wire
		(pts
			(xy 68.58 260.35) (xy 68.58 264.16)
		)
		(stroke
			(width 0)
			(type default)
		)
	)
	(wire
		(pts
			(xy 331.47 95.25) (xy 351.79 95.25)
		)
		(stroke
			(width 0)
			(type default)
		)
	)
	(polyline
		(pts
			(xy 205.74 214.63) (xy 269.24 214.63)
		)
		(stroke
			(width 0)
			(type default)
		)
	)
	(wire
		(pts
			(xy 203.2 154.94) (xy 220.98 154.94)
		)
		(stroke
			(width 0)
			(type default)
		)
	)
	(wire
		(pts
			(xy 190.5 262.89) (xy 190.5 265.43)
		)
		(stroke
			(width 0)
			(type default)
		)
	)
	(polyline
		(pts
			(xy 82.55 44.45) (xy 19.05 44.45)
		)
		(stroke
			(width 0)
			(type solid)
		)
	)
	(bus
		(pts
			(xy 53.34 181.61) (xy 53.34 184.15)
		)
		(stroke
			(width 0)
			(type default)
		)
	)
	(wire
		(pts
			(xy 289.56 231.14) (xy 311.15 231.14)
		)
		(stroke
			(width 0)
			(type default)
		)
	)
	(wire
		(pts
			(xy 280.67 43.18) (xy 280.67 44.45)
		)
		(stroke
			(width 0)
			(type default)
		)
	)
	(wire
		(pts
			(xy 306.07 157.48) (xy 312.42 157.48)
		)
		(stroke
			(width 0)
			(type default)
		)
	)
	(wire
		(pts
			(xy 116.84 154.94) (xy 116.84 157.48)
		)
		(stroke
			(width 0)
			(type default)
		)
	)
	(wire
		(pts
			(xy 247.65 19.05) (xy 247.65 21.59)
		)
		(stroke
			(width 0)
			(type default)
		)
	)
	(wire
		(pts
			(xy 175.26 213.36) (xy 184.15 213.36)
		)
		(stroke
			(width 0)
			(type default)
		)
	)
	(wire
		(pts
			(xy 57.15 96.52) (xy 68.58 96.52)
		)
		(stroke
			(width 0)
			(type default)
		)
	)
	(wire
		(pts
			(xy 110.49 200.66) (xy 137.16 200.66)
		)
		(stroke
			(width 0)
			(type default)
		)
	)
	(wire
		(pts
			(xy 219.71 71.12) (xy 232.41 71.12)
		)
		(stroke
			(width 0)
			(type default)
		)
	)
	(wire
		(pts
			(xy 229.87 115.57) (xy 229.87 118.11)
		)
		(stroke
			(width 0)
			(type default)
		)
	)
	(wire
		(pts
			(xy 57.15 78.74) (xy 68.58 78.74)
		)
		(stroke
			(width 0)
			(type default)
		)
	)
	(wire
		(pts
			(xy 142.24 35.56) (xy 130.81 35.56)
		)
		(stroke
			(width 0)
			(type default)
		)
	)
	(wire
		(pts
			(xy 151.13 78.74) (xy 175.26 78.74)
		)
		(stroke
			(width 0)
			(type default)
		)
	)
	(wire
		(pts
			(xy 317.5 35.56) (xy 317.5 38.1)
		)
		(stroke
			(width 0)
			(type default)
		)
	)
	(wire
		(pts
			(xy 378.46 99.695) (xy 396.24 99.695)
		)
		(stroke
			(width 0)
			(type default)
		)
	)
	(bus
		(pts
			(xy 318.77 185.42) (xy 318.77 186.69)
		)
		(stroke
			(width 0)
			(type default)
		)
	)
	(wire
		(pts
			(xy 25.4 60.96) (xy 52.07 60.96)
		)
		(stroke
			(width 0)
			(type default)
		)
	)
	(wire
		(pts
			(xy 327.66 19.05) (xy 317.5 19.05)
		)
		(stroke
			(width 0)
			(type default)
		)
	)
	(wire
		(pts
			(xy 57.15 254) (xy 68.58 254)
		)
		(stroke
			(width 0)
			(type default)
		)
	)
	(wire
		(pts
			(xy 120.65 26.67) (xy 120.65 29.21)
		)
		(stroke
			(width 0)
			(type default)
		)
	)
	(wire
		(pts
			(xy 57.15 260.35) (xy 68.58 260.35)
		)
		(stroke
			(width 0)
			(type default)
		)
	)
	(wire
		(pts
			(xy 106.68 238.76) (xy 106.68 241.3)
		)
		(stroke
			(width 0)
			(type default)
		)
	)
	(wire
		(pts
			(xy 248.92 152.4) (xy 248.92 154.94)
		)
		(stroke
			(width 0)
			(type default)
		)
	)
	(wire
		(pts
			(xy 406.4 214.63) (xy 406.4 217.17)
		)
		(stroke
			(width 0)
			(type default)
		)
	)
	(wire
		(pts
			(xy 262.89 231.14) (xy 262.89 232.41)
		)
		(stroke
			(width 0)
			(type default)
		)
	)
	(wire
		(pts
			(xy 135.89 167.64) (xy 135.89 154.94)
		)
		(stroke
			(width 0)
			(type default)
		)
	)
	(bus
		(pts
			(xy 335.28 127) (xy 335.28 124.46)
		)
		(stroke
			(width 0)
			(type default)
		)
	)
	(wire
		(pts
			(xy 196.85 234.95) (xy 217.17 234.95)
		)
		(stroke
			(width 0)
			(type default)
		)
	)
	(wire
		(pts
			(xy 68.58 100.33) (xy 68.58 102.87)
		)
		(stroke
			(width 0)
			(type default)
		)
	)
	(wire
		(pts
			(xy 219.71 111.76) (xy 223.52 111.76)
		)
		(stroke
			(width 0)
			(type default)
		)
	)
	(wire
		(pts
			(xy 142.24 19.05) (xy 152.4 19.05)
		)
		(stroke
			(width 0)
			(type default)
		)
	)
	(wire
		(pts
			(xy 223.52 114.3) (xy 223.52 118.11)
		)
		(stroke
			(width 0)
			(type default)
		)
	)
	(wire
		(pts
			(xy 259.08 179.07) (xy 261.62 179.07)
		)
		(stroke
			(width 0)
			(type default)
		)
	)
	(wire
		(pts
			(xy 68.58 102.87) (xy 68.58 105.41)
		)
		(stroke
			(width 0)
			(type default)
		)
	)
	(wire
		(pts
			(xy 106.68 213.36) (xy 106.68 220.98)
		)
		(stroke
			(width 0)
			(type default)
		)
	)
	(wire
		(pts
			(xy 347.98 184.15) (xy 373.38 184.15)
		)
		(stroke
			(width 0)
			(type default)
		)
	)
	(wire
		(pts
			(xy 57.15 267.97) (xy 68.58 267.97)
		)
		(stroke
			(width 0)
			(type default)
		)
	)
	(wire
		(pts
			(xy 68.58 107.95) (xy 68.58 111.76)
		)
		(stroke
			(width 0)
			(type default)
		)
	)
	(wire
		(pts
			(xy 57.15 72.39) (xy 68.58 72.39)
		)
		(stroke
			(width 0)
			(type default)
		)
	)
	(wire
		(pts
			(xy 68.58 114.3) (xy 68.58 116.84)
		)
		(stroke
			(width 0)
			(type default)
		)
	)
	(bus
		(pts
			(xy 149.86 82.55) (xy 149.86 85.09)
		)
		(stroke
			(width 0)
			(type default)
		)
	)
	(wire
		(pts
			(xy 175.26 205.74) (xy 191.77 205.74)
		)
		(stroke
			(width 0)
			(type default)
		)
	)
	(wire
		(pts
			(xy 144.78 120.65) (xy 144.78 124.46)
		)
		(stroke
			(width 0)
			(type default)
		)
	)
	(wire
		(pts
			(xy 336.55 128.27) (xy 351.79 128.27)
		)
		(stroke
			(width 0)
			(type default)
		)
	)
	(wire
		(pts
			(xy 379.73 184.15) (xy 375.92 184.15)
		)
		(stroke
			(width 0)
			(type default)
		)
	)
	(wire
		(pts
			(xy 57.15 58.42) (xy 68.58 58.42)
		)
		(stroke
			(width 0)
			(type default)
		)
	)
	(wire
		(pts
			(xy 195.58 162.56) (xy 195.58 163.83)
		)
		(stroke
			(width 0)
			(type default)
		)
	)
	(bus
		(pts
			(xy 134.62 87.63) (xy 149.86 87.63)
		)
		(stroke
			(width 0)
			(type default)
		)
	)
	(wire
		(pts
			(xy 269.24 19.05) (xy 259.08 19.05)
		)
		(stroke
			(width 0)
			(type default)
		)
	)
	(bus
		(pts
			(xy 196.85 274.32) (xy 199.39 274.32)
		)
		(stroke
			(width 0)
			(type default)
		)
	)
	(wire
		(pts
			(xy 25.4 227.33) (xy 52.07 227.33)
		)
		(stroke
			(width 0)
			(type default)
		)
	)
	(wire
		(pts
			(xy 290.83 19.05) (xy 290.83 21.59)
		)
		(stroke
			(width 0)
			(type default)
		)
	)
	(wire
		(pts
			(xy 68.58 229.87) (xy 68.58 232.41)
		)
		(stroke
			(width 0)
			(type default)
		)
	)
	(wire
		(pts
			(xy 377.19 181.61) (xy 379.73 181.61)
		)
		(stroke
			(width 0)
			(type default)
		)
	)
	(wire
		(pts
			(xy 405.13 207.01) (xy 406.4 207.01)
		)
		(stroke
			(width 0)
			(type default)
		)
	)
	(wire
		(pts
			(xy 269.24 35.56) (xy 269.24 38.1)
		)
		(stroke
			(width 0)
			(type default)
		)
	)
	(wire
		(pts
			(xy 331.47 110.49) (xy 351.79 110.49)
		)
		(stroke
			(width 0)
			(type default)
		)
	)
	(polyline
		(pts
			(xy 19.05 215.9) (xy 82.55 215.9)
		)
		(stroke
			(width 0)
			(type solid)
		)
	)
	(wire
		(pts
			(xy 57.15 55.88) (xy 68.58 55.88)
		)
		(stroke
			(width 0)
			(type default)
		)
	)
	(wire
		(pts
			(xy 196.85 242.57) (xy 217.17 242.57)
		)
		(stroke
			(width 0)
			(type default)
		)
	)
	(wire
		(pts
			(xy 54.61 180.34) (xy 137.16 180.34)
		)
		(stroke
			(width 0)
			(type default)
		)
	)
	(wire
		(pts
			(xy 347.98 168.91) (xy 379.73 168.91)
		)
		(stroke
			(width 0)
			(type default)
		)
	)
	(wire
		(pts
			(xy 294.64 152.4) (xy 294.64 157.48)
		)
		(stroke
			(width 0)
			(type default)
		)
	)
	(wire
		(pts
			(xy 54.61 182.88) (xy 137.16 182.88)
		)
		(stroke
			(width 0)
			(type default)
		)
	)
	(wire
		(pts
			(xy 175.26 172.72) (xy 184.15 172.72)
		)
		(stroke
			(width 0)
			(type default)
		)
	)
	(wire
		(pts
			(xy 152.4 19.05) (xy 152.4 21.59)
		)
		(stroke
			(width 0)
			(type default)
		)
	)
	(polyline
		(pts
			(xy 96.52 171.45) (xy 119.38 171.45)
		)
		(stroke
			(width 0)
			(type default)
		)
	)
	(wire
		(pts
			(xy 320.04 184.15) (xy 342.9 184.15)
		)
		(stroke
			(width 0)
			(type default)
		)
	)
	(wire
		(pts
			(xy 175.26 114.3) (xy 162.56 114.3)
		)
		(stroke
			(width 0)
			(type default)
		)
	)
	(wire
		(pts
			(xy 336.55 120.65) (xy 351.79 120.65)
		)
		(stroke
			(width 0)
			(type default)
		)
	)
	(wire
		(pts
			(xy 289.56 203.2) (xy 311.15 203.2)
		)
		(stroke
			(width 0)
			(type default)
		)
	)
	(wire
		(pts
			(xy 114.3 19.05) (xy 120.65 19.05)
		)
		(stroke
			(width 0)
			(type default)
		)
	)
	(wire
		(pts
			(xy 152.4 26.67) (xy 152.4 29.21)
		)
		(stroke
			(width 0)
			(type default)
		)
	)
	(polyline
		(pts
			(xy 73.66 212.09) (xy 73.66 184.15)
		)
		(stroke
			(width 0)
			(type default)
		)
	)
	(bus
		(pts
			(xy 53.34 201.93) (xy 53.34 204.47)
		)
		(stroke
			(width 0)
			(type default)
		)
	)
	(bus
		(pts
			(xy 149.86 59.69) (xy 149.86 64.77)
		)
		(stroke
			(width 0)
			(type default)
		)
	)
	(polyline
		(pts
			(xy 19.05 133.35) (xy 19.05 44.45)
		)
		(stroke
			(width 0)
			(type solid)
		)
	)
	(wire
		(pts
			(xy 114.3 19.05) (xy 114.3 24.13)
		)
		(stroke
			(width 0)
			(type default)
		)
	)
	(polyline
		(pts
			(xy 323.85 85.09) (xy 323.85 113.03)
		)
		(stroke
			(width 0)
			(type default)
		)
	)
	(wire
		(pts
			(xy 379.73 129.54) (xy 379.73 128.27)
		)
		(stroke
			(width 0)
			(type default)
		)
	)
	(wire
		(pts
			(xy 134.62 125.73) (xy 134.62 132.08)
		)
		(stroke
			(width 0)
			(type default)
		)
	)
	(wire
		(pts
			(xy 129.54 215.9) (xy 137.16 215.9)
		)
		(stroke
			(width 0)
			(type default)
		)
	)
	(bus
		(pts
			(xy 149.86 87.63) (xy 149.86 90.17)
		)
		(stroke
			(width 0)
			(type default)
		)
	)
	(wire
		(pts
			(xy 57.15 107.95) (xy 68.58 107.95)
		)
		(stroke
			(width 0)
			(type default)
		)
	)
	(wire
		(pts
			(xy 129.54 215.9) (xy 129.54 220.98)
		)
		(stroke
			(width 0)
			(type default)
		)
	)
	(polyline
		(pts
			(xy 406.4 146.05) (xy 279.4 146.05)
		)
		(stroke
			(width 0)
			(type default)
		)
	)
	(bus
		(pts
			(xy 53.34 189.23) (xy 53.34 191.77)
		)
		(stroke
			(width 0)
			(type default)
		)
	)
	(wire
		(pts
			(xy 320.04 171.45) (xy 342.9 171.45)
		)
		(stroke
			(width 0)
			(type default)
		)
	)
	(wire
		(pts
			(xy 246.38 186.69) (xy 246.38 198.12)
		)
		(stroke
			(width 0)
			(type default)
		)
	)
	(wire
		(pts
			(xy 375.92 184.15) (xy 375.92 179.07)
		)
		(stroke
			(width 0)
			(type default)
		)
	)
	(label "GBE_RGMII.RXD3"
		(at 25.4 88.9 0)
		(effects
			(font
				(size 1.27 1.27)
			)
			(justify left bottom)
		)
	)
	(label "GBE_AVDDL{slash}PLL"
		(at 297.18 35.56 0)
		(effects
			(font
				(size 1.27 1.27)
			)
			(justify left bottom)
		)
	)
	(label "GBE2_P"
		(at 331.47 107.95 0)
		(effects
			(font
				(size 1.27 1.27)
			)
			(justify left bottom)
		)
	)
	(label "ETH_RMII.RXD0"
		(at 55.88 200.66 0)
		(effects
			(font
				(size 1.27 1.27)
			)
			(justify left bottom)
		)
	)
	(label "ETH_LED_LINK-"
		(at 25.4 264.16 0)
		(effects
			(font
				(size 1.27 1.27)
			)
			(justify left bottom)
		)
	)
	(label "GBE_RGMII.RXD0"
		(at 153.67 91.44 0)
		(effects
			(font
				(size 1.27 1.27)
			)
			(justify left bottom)
		)
	)
	(label "ETH_RMII.TXD0"
		(at 55.88 190.5 0)
		(effects
			(font
				(size 1.27 1.27)
			)
			(justify left bottom)
		)
	)
	(label "ETH1_N"
		(at 196.85 234.95 0)
		(effects
			(font
				(size 1.27 1.27)
			)
			(justify left bottom)
		)
	)
	(label "GBE_LED_SPD-"
		(at 238.76 93.98 180)
		(effects
			(font
				(size 1.27 1.27)
			)
			(justify right bottom)
		)
	)
	(label "HDMI.D0_P"
		(at 323.85 176.53 0)
		(effects
			(font
				(size 1.27 1.27)
			)
			(justify left bottom)
		)
	)
	(label "ETH2_N"
		(at 266.7 198.12 180)
		(effects
			(font
				(size 1.27 1.27)
			)
			(justify right bottom)
		)
	)
	(label "GBE_RGMII.REFCLK"
		(at 25.4 81.28 0)
		(effects
			(font
				(size 1.27 1.27)
			)
			(justify left bottom)
		)
	)
	(label "GBE_RGMII.TXD0"
		(at 153.67 73.66 0)
		(effects
			(font
				(size 1.27 1.27)
			)
			(justify left bottom)
		)
	)
	(label "ETH_PHY_RXDO"
		(at 25.4 256.54 0)
		(effects
			(font
				(size 1.27 1.27)
			)
			(justify left bottom)
		)
	)
	(label "GBE_RGMII.TXD3"
		(at 153.67 81.28 0)
		(effects
			(font
				(size 1.27 1.27)
			)
			(justify left bottom)
		)
	)
	(label "ETH_PHY_RXER"
		(at 120.65 205.74 0)
		(effects
			(font
				(size 1.27 1.27)
			)
			(justify left bottom)
		)
	)
	(label "GBE_LED_LINK-"
		(at 25.4 105.41 0)
		(effects
			(font
				(size 1.27 1.27)
			)
			(justify left bottom)
		)
	)
	(label "GBE_ISET"
		(at 229.87 109.22 180)
		(effects
			(font
				(size 1.27 1.27)
			)
			(justify right bottom)
		)
	)
	(label "HDMI_CONN_D2_N"
		(at 355.6 168.91 0)
		(effects
			(font
				(size 1.27 1.27)
			)
			(justify left bottom)
		)
	)
	(label "ETH_RMII.~{RESET}"
		(at 57.15 172.72 0)
		(effects
			(font
				(size 1.27 1.27)
			)
			(justify left bottom)
		)
	)
	(label "GBE_AVDDH"
		(at 168.91 35.56 180)
		(effects
			(font
				(size 1.27 1.27)
			)
			(justify right bottom)
		)
	)
	(label "GBE_RGMII.RXD1"
		(at 153.67 93.98 0)
		(effects
			(font
				(size 1.27 1.27)
			)
			(justify left bottom)
		)
	)
	(label "GBE_RGMII.TXD1"
		(at 153.67 76.2 0)
		(effects
			(font
				(size 1.27 1.27)
			)
			(justify left bottom)
		)
	)
	(label "ETH_LED_SPD-"
		(at 191.77 208.28 180)
		(effects
			(font
				(size 1.27 1.27)
			)
			(justify right bottom)
		)
	)
	(label "ETH_LED_SPD-"
		(at 25.4 267.97 0)
		(effects
			(font
				(size 1.27 1.27)
			)
			(justify left bottom)
		)
	)
	(label "HDMI_CONN_CLK_P"
		(at 355.6 181.61 0)
		(effects
			(font
				(size 1.27 1.27)
			)
			(justify left bottom)
		)
	)
	(label "GBE_RGMII.~{RESET}"
		(at 153.67 55.88 0)
		(effects
			(font
				(size 1.27 1.27)
			)
			(justify left bottom)
		)
	)
	(label "GBE_RGMII.RXD1"
		(at 25.4 60.96 0)
		(effects
			(font
				(size 1.27 1.27)
			)
			(justify left bottom)
		)
	)
	(label "HDMI_CONN_CLK_N"
		(at 289.56 236.22 0)
		(effects
			(font
				(size 1.27 1.27)
			)
			(justify left bottom)
		)
	)
	(label "GBE4_P"
		(at 232.41 63.5 180)
		(effects
			(font
				(size 1.27 1.27)
			)
			(justify right bottom)
		)
	)
	(label "ETH_XO"
		(at 129.54 215.9 0)
		(effects
			(font
				(size 1.27 1.27)
			)
			(justify left bottom)
		)
	)
	(label "GBE3_N"
		(at 232.41 68.58 180)
		(effects
			(font
				(size 1.27 1.27)
			)
			(justify right bottom)
		)
	)
	(label "ETH_RMII.TXD1"
		(at 55.88 193.04 0)
		(effects
			(font
				(size 1.27 1.27)
			)
			(justify left bottom)
		)
	)
	(label "GBE_RGMII.REFCLK"
		(at 25.4 114.3 0)
		(effects
			(font
				(size 1.27 1.27)
			)
			(justify left bottom)
		)
	)
	(label "POE_ETH.VC1"
		(at 203.2 260.35 0)
		(effects
			(font
				(size 1.27 1.27)
			)
			(justify left bottom)
		)
	)
	(label "HDMI_CONN_D1_P"
		(at 289.56 208.28 0)
		(effects
			(font
				(size 1.27 1.27)
			)
			(justify left bottom)
		)
	)
	(label "ETH_LED_SPD+"
		(at 259.08 254 180)
		(effects
			(font
				(size 1.27 1.27)
			)
			(justify right bottom)
		)
	)
	(label "ETH_LED_LINK+"
		(at 245.11 239.395 0)
		(effects
			(font
				(size 1.27 1.27)
			)
			(justify left bottom)
		)
	)
	(label "GBE_RGMII.MDIO"
		(at 129.54 66.04 0)
		(effects
			(font
				(size 1.27 1.27)
			)
			(justify left bottom)
		)
	)
	(label "ETH_LED_LINK-"
		(at 191.77 205.74 180)
		(effects
			(font
				(size 1.27 1.27)
			)
			(justify right bottom)
		)
	)
	(label "ETH_PHY_TXD1"
		(at 120.65 193.04 0)
		(effects
			(font
				(size 1.27 1.27)
			)
			(justify left bottom)
		)
	)
	(label "ETH_RMII.~{RESET}"
		(at 36.83 172.72 0)
		(effects
			(font
				(size 1.27 1.27)
			)
			(justify left bottom)
		)
	)
	(label "ETH_ISET"
		(at 176.53 213.36 0)
		(effects
			(font
				(size 1.27 1.27)
			)
			(justify left bottom)
		)
	)
	(label "ETH1_P"
		(at 196.85 237.49 0)
		(effects
			(font
				(size 1.27 1.27)
			)
			(justify left bottom)
		)
	)
	(label "ETH_3V3"
		(at 181.61 245.11 0)
		(effects
			(font
				(size 1.27 1.27)
			)
			(justify left bottom)
		)
	)
	(label "ETH_VDDCR"
		(at 195.58 172.72 180)
		(effects
			(font
				(size 1.27 1.27)
			)
			(justify right bottom)
		)
	)
	(label "ETH_RMII.RXD1"
		(at 55.88 203.2 0)
		(effects
			(font
				(size 1.27 1.27)
			)
			(justify left bottom)
		)
	)
	(label "GBE_RGMII.RX_DV"
		(at 25.4 111.76 0)
		(effects
			(font
				(size 1.27 1.27)
			)
			(justify left bottom)
		)
	)
	(label "ETH_PHY_RXER"
		(at 25.4 260.35 0)
		(effects
			(font
				(size 1.27 1.27)
			)
			(justify left bottom)
		)
	)
	(label "GBE_RGMII.RXD0"
		(at 25.4 96.52 0)
		(effects
			(font
				(size 1.27 1.27)
			)
			(justify left bottom)
		)
	)
	(label "HDMI_CONN_D2_N"
		(at 289.56 205.74 0)
		(effects
			(font
				(size 1.27 1.27)
			)
			(justify left bottom)
		)
	)
	(label "ETH_LED_SPD-"
		(at 25.4 243.84 0)
		(effects
			(font
				(size 1.27 1.27)
			)
			(justify left bottom)
		)
	)
	(label "ETH_RMII.MDIO"
		(at 36.83 180.34 0)
		(effects
			(font
				(size 1.27 1.27)
			)
			(justify left bottom)
		)
	)
	(label "ETH_PHY_RXD1"
		(at 120.65 203.2 0)
		(effects
			(font
				(size 1.27 1.27)
			)
			(justify left bottom)
		)
	)
	(label "ETH_RMII.MDC"
		(at 57.15 182.88 0)
		(effects
			(font
				(size 1.27 1.27)
			)
			(justify left bottom)
		)
	)
	(label "GBE_RGMII.REFCLK"
		(at 153.67 106.68 0)
		(effects
			(font
				(size 1.27 1.27)
			)
			(justify left bottom)
		)
	)
	(label "ETH_PHY_REFCLK"
		(at 120.65 175.26 0)
		(effects
			(font
				(size 1.27 1.27)
			)
			(justify left bottom)
		)
	)
	(label "GBE_RGMII.RXD1"
		(at 25.4 93.98 0)
		(effects
			(font
				(size 1.27 1.27)
			)
			(justify left bottom)
		)
	)
	(label "POE_ETH.VC2"
		(at 203.2 262.89 0)
		(effects
			(font
				(size 1.27 1.27)
			)
			(justify left bottom)
		)
	)
	(label "HDMI_CONN_D0_N"
		(at 355.6 179.07 0)
		(effects
			(font
				(size 1.27 1.27)
			)
			(justify left bottom)
		)
	)
	(label "GBE_RGMII.GTR_CLK"
		(at 25.4 67.31 0)
		(effects
			(font
				(size 1.27 1.27)
			)
			(justify left bottom)
		)
	)
	(label "HDMI.CLK_P"
		(at 323.85 181.61 0)
		(effects
			(font
				(size 1.27 1.27)
			)
			(justify left bottom)
		)
	)
	(label "ETH_RMII.RX_DV"
		(at 55.88 198.12 0)
		(effects
			(font
				(size 1.27 1.27)
			)
			(justify left bottom)
		)
	)
	(label "ETH2_P"
		(at 196.85 242.57 0)
		(effects
			(font
				(size 1.27 1.27)
			)
			(justify left bottom)
		)
	)
	(label "GBE_XI"
		(at 166.37 111.76 0)
		(effects
			(font
				(size 1.27 1.27)
			)
			(justify left bottom)
		)
	)
	(label "HDMI_CONN_CLK_P"
		(at 289.56 233.68 0)
		(effects
			(font
				(size 1.27 1.27)
			)
			(justify left bottom)
		)
	)
	(label "ETH_LED_LINK-"
		(at 259.08 243.84 180)
		(effects
			(font
				(size 1.27 1.27)
			)
			(justify right bottom)
		)
	)
	(label "GBE_LED_SPD-"
		(at 25.4 102.87 0)
		(effects
			(font
				(size 1.27 1.27)
			)
			(justify left bottom)
		)
	)
	(label "POE_ETH.VC3"
		(at 203.2 265.43 0)
		(effects
			(font
				(size 1.27 1.27)
			)
			(justify left bottom)
		)
	)
	(label "GBE3_P"
		(at 232.41 71.12 180)
		(effects
			(font
				(size 1.27 1.27)
			)
			(justify right bottom)
		)
	)
	(label "ETH_LED_LINK-"
		(at 25.4 240.03 0)
		(effects
			(font
				(size 1.27 1.27)
			)
			(justify left bottom)
		)
	)
	(label "HDMI_CONN_CLK_N"
		(at 355.6 184.15 0)
		(effects
			(font
				(size 1.27 1.27)
			)
			(justify left bottom)
		)
	)
	(label "ETH1_P"
		(at 266.7 190.5 180)
		(effects
			(font
				(size 1.27 1.27)
			)
			(justify right bottom)
		)
	)
	(label "GBE_RGMII.RXD2"
		(at 153.67 96.52 0)
		(effects
			(font
				(size 1.27 1.27)
			)
			(justify left bottom)
		)
	)
	(label "GBE_LED_LINK-"
		(at 238.76 96.52 180)
		(effects
			(font
				(size 1.27 1.27)
			)
			(justify right bottom)
		)
	)
	(label "HDMI_CONN_D2_P"
		(at 355.6 166.37 0)
		(effects
			(font
				(size 1.27 1.27)
			)
			(justify left bottom)
		)
	)
	(label "GBE_RGMII.RX_DV"
		(at 25.4 78.74 0)
		(effects
			(font
				(size 1.27 1.27)
			)
			(justify left bottom)
		)
	)
	(label "GBE_LED_SPD+"
		(at 392.43 114.3 180)
		(effects
			(font
				(size 1.27 1.27)
			)
			(justify right bottom)
		)
	)
	(label "ETH_XI"
		(at 129.54 213.36 0)
		(effects
			(font
				(size 1.27 1.27)
			)
			(justify left bottom)
		)
	)
	(label "GBE_RGMII.~{INT}"
		(at 25.4 74.93 0)
		(effects
			(font
				(size 1.27 1.27)
			)
			(justify left bottom)
		)
	)
	(label "GBE1_P"
		(at 331.47 113.03 0)
		(effects
			(font
				(size 1.27 1.27)
			)
			(justify left bottom)
		)
	)
	(label "HDMI.D1_N"
		(at 323.85 173.99 0)
		(effects
			(font
				(size 1.27 1.27)
			)
			(justify left bottom)
		)
	)
	(label "HDMI_CONN_D0_P"
		(at 355.6 176.53 0)
		(effects
			(font
				(size 1.27 1.27)
			)
			(justify left bottom)
		)
	)
	(label "GBE_RGMII.TXD2"
		(at 153.67 78.74 0)
		(effects
			(font
				(size 1.27 1.27)
			)
			(justify left bottom)
		)
	)
	(label "ETH_PHY_RX_DV"
		(at 25.4 227.33 0)
		(effects
			(font
				(size 1.27 1.27)
			)
			(justify left bottom)
		)
	)
	(label "ETH_PHY_RXD1"
		(at 25.4 254 0)
		(effects
			(font
				(size 1.27 1.27)
			)
			(justify left bottom)
		)
	)
	(label "ETH_PHY_RX_DV"
		(at 120.65 198.12 0)
		(effects
			(font
				(size 1.27 1.27)
			)
			(justify left bottom)
		)
	)
	(label "GBE_RGMII.~{RESET}"
		(at 129.54 55.88 0)
		(effects
			(font
				(size 1.27 1.27)
			)
			(justify left bottom)
		)
	)
	(label "POE_GBE.VC3"
		(at 337.82 125.73 0)
		(effects
			(font
				(size 1.27 1.27)
			)
			(justify left bottom)
		)
	)
	(label "ETH_PHY_TXEN"
		(at 120.65 187.96 0)
		(effects
			(font
				(size 1.27 1.27)
			)
			(justify left bottom)
		)
	)
	(label "ETH_RMII.MDIO"
		(at 57.15 180.34 0)
		(effects
			(font
				(size 1.27 1.27)
			)
			(justify left bottom)
		)
	)
	(label "POE_GBE.VC1"
		(at 337.82 120.65 0)
		(effects
			(font
				(size 1.27 1.27)
			)
			(justify left bottom)
		)
	)
	(label "HDMI_CONN_D1_P"
		(at 355.6 171.45 0)
		(effects
			(font
				(size 1.27 1.27)
			)
			(justify left bottom)
		)
	)
	(label "GBE_RGMII.RX_DV"
		(at 153.67 88.9 0)
		(effects
			(font
				(size 1.27 1.27)
			)
			(justify left bottom)
		)
	)
	(label "GBE_RGMII.RXD3"
		(at 153.67 99.06 0)
		(effects
			(font
				(size 1.27 1.27)
			)
			(justify left bottom)
		)
	)
	(label "GBE_RGMII.MDIO"
		(at 153.67 66.04 0)
		(effects
			(font
				(size 1.27 1.27)
			)
			(justify left bottom)
		)
	)
	(label "GBE_RGMII.RXD3"
		(at 25.4 55.88 0)
		(effects
			(font
				(size 1.27 1.27)
			)
			(justify left bottom)
		)
	)
	(label "GBE1_N"
		(at 232.41 83.82 180)
		(effects
			(font
				(size 1.27 1.27)
			)
			(justify right bottom)
		)
	)
	(label "GBE4_N"
		(at 331.47 95.25 0)
		(effects
			(font
				(size 1.27 1.27)
			)
			(justify left bottom)
		)
	)
	(label "HDMI_5V"
		(at 313.69 157.48 0)
		(effects
			(font
				(size 1.27 1.27)
			)
			(justify left bottom)
		)
	)
	(label "GBE_RGMII.TX_EN"
		(at 153.67 71.12 0)
		(effects
			(font
				(size 1.27 1.27)
			)
			(justify left bottom)
		)
	)
	(label "GBE2_P"
		(at 232.41 78.74 180)
		(effects
			(font
				(size 1.27 1.27)
			)
			(justify right bottom)
		)
	)
	(label "HDMI_CONN_D0_N"
		(at 289.56 231.14 0)
		(effects
			(font
				(size 1.27 1.27)
			)
			(justify left bottom)
		)
	)
	(label "HDMI_CONN_D2_P"
		(at 289.56 203.2 0)
		(effects
			(font
				(size 1.27 1.27)
			)
			(justify left bottom)
		)
	)
	(label "GBE_CONN_COMM"
		(at 331.47 115.57 0)
		(effects
			(font
				(size 1.27 1.27)
			)
			(justify left bottom)
		)
	)
	(label "ETH_PHY_RX_DV"
		(at 25.4 251.46 0)
		(effects
			(font
				(size 1.27 1.27)
			)
			(justify left bottom)
		)
	)
	(label "ETH2_P"
		(at 266.7 195.58 180)
		(effects
			(font
				(size 1.27 1.27)
			)
			(justify right bottom)
		)
	)
	(label "HDMI_CONN_D0_P"
		(at 289.56 228.6 0)
		(effects
			(font
				(size 1.27 1.27)
			)
			(justify left bottom)
		)
	)
	(label "ETH_PHY_TXDO"
		(at 120.65 190.5 0)
		(effects
			(font
				(size 1.27 1.27)
			)
			(justify left bottom)
		)
	)
	(label "GBE_XO"
		(at 166.37 114.3 0)
		(effects
			(font
				(size 1.27 1.27)
			)
			(justify left bottom)
		)
	)
	(label "ETH_3V3"
		(at 219.71 154.94 180)
		(effects
			(font
				(size 1.27 1.27)
			)
			(justify right bottom)
		)
	)
	(label "GBE_RGMII.MDC"
		(at 153.67 63.5 0)
		(effects
			(font
				(size 1.27 1.27)
			)
			(justify left bottom)
		)
	)
	(label "ETH_PHY_RXER"
		(at 25.4 236.22 0)
		(effects
			(font
				(size 1.27 1.27)
			)
			(justify left bottom)
		)
	)
	(label "GBE_RGMII.RXD2"
		(at 25.4 91.44 0)
		(effects
			(font
				(size 1.27 1.27)
			)
			(justify left bottom)
		)
	)
	(label "GBE_RGMII.GTR_CLK"
		(at 25.4 100.33 0)
		(effects
			(font
				(size 1.27 1.27)
			)
			(justify left bottom)
		)
	)
	(label "GBE1_N"
		(at 331.47 110.49 0)
		(effects
			(font
				(size 1.27 1.27)
			)
			(justify left bottom)
		)
	)
	(label "GBE3_P"
		(at 331.47 102.87 0)
		(effects
			(font
				(size 1.27 1.27)
			)
			(justify left bottom)
		)
	)
	(label "GBE_LED_SPD-"
		(at 393.7 109.855 180)
		(effects
			(font
				(size 1.27 1.27)
			)
			(justify right bottom)
		)
	)
	(label "ETH1_N"
		(at 266.7 193.04 180)
		(effects
			(font
				(size 1.27 1.27)
			)
			(justify right bottom)
		)
	)
	(label "ETH_PHY_RXDO"
		(at 120.65 200.66 0)
		(effects
			(font
				(size 1.27 1.27)
			)
			(justify left bottom)
		)
	)
	(label "ETH2_N"
		(at 196.85 240.03 0)
		(effects
			(font
				(size 1.27 1.27)
			)
			(justify left bottom)
		)
	)
	(label "ETH_PHY_RXDO"
		(at 25.4 232.41 0)
		(effects
			(font
				(size 1.27 1.27)
			)
			(justify left bottom)
		)
	)
	(label "GBE_LED_SPD-"
		(at 25.4 69.85 0)
		(effects
			(font
				(size 1.27 1.27)
			)
			(justify left bottom)
		)
	)
	(label "POE_GBE.VC2"
		(at 337.82 123.19 0)
		(effects
			(font
				(size 1.27 1.27)
			)
			(justify left bottom)
		)
	)
	(label "ETH_RMII.TXEN"
		(at 55.88 187.96 0)
		(effects
			(font
				(size 1.27 1.27)
			)
			(justify left bottom)
		)
	)
	(label "GBE_RGMII.~{INT}"
		(at 153.67 58.42 0)
		(effects
			(font
				(size 1.27 1.27)
			)
			(justify left bottom)
		)
	)
	(label "GBE4_N"
		(at 232.41 60.96 180)
		(effects
			(font
				(size 1.27 1.27)
			)
			(justify right bottom)
		)
	)
	(label "GBE_LED_LINK-"
		(at 393.7 104.14 180)
		(effects
			(font
				(size 1.27 1.27)
			)
			(justify right bottom)
		)
	)
	(label "GBE4_P"
		(at 331.47 97.79 0)
		(effects
			(font
				(size 1.27 1.27)
			)
			(justify left bottom)
		)
	)
	(label "HDMI_CONN_D1_N"
		(at 355.6 173.99 0)
		(effects
			(font
				(size 1.27 1.27)
			)
			(justify left bottom)
		)
	)
	(label "GBE1_P"
		(at 232.41 86.36 180)
		(effects
			(font
				(size 1.27 1.27)
			)
			(justify right bottom)
		)
	)
	(label "HDMI.CLK_N"
		(at 323.85 184.15 0)
		(effects
			(font
				(size 1.27 1.27)
			)
			(justify left bottom)
		)
	)
	(label "POE_GBE.VC4"
		(at 337.82 128.27 0)
		(effects
			(font
				(size 1.27 1.27)
			)
			(justify left bottom)
		)
	)
	(label "POE_ETH.VC4"
		(at 203.2 267.97 0)
		(effects
			(font
				(size 1.27 1.27)
			)
			(justify left bottom)
		)
	)
	(label "HDMI_CONN_D1_N"
		(at 289.56 210.82 0)
		(effects
			(font
				(size 1.27 1.27)
			)
			(justify left bottom)
		)
	)
	(label "GBE_RGMII.RXD2"
		(at 25.4 58.42 0)
		(effects
			(font
				(size 1.27 1.27)
			)
			(justify left bottom)
		)
	)
	(label "GBE_RGMII.~{INT}"
		(at 25.4 107.95 0)
		(effects
			(font
				(size 1.27 1.27)
			)
			(justify left bottom)
		)
	)
	(label "ETH_RMII.REFCLK"
		(at 57.15 175.26 0)
		(effects
			(font
				(size 1.27 1.27)
			)
			(justify left bottom)
		)
	)
	(label "ETH_LED_SPD-"
		(at 259.08 249.555 180)
		(effects
			(font
				(size 1.27 1.27)
			)
			(justify right bottom)
		)
	)
	(label "GBE_LED_LINK-"
		(at 25.4 72.39 0)
		(effects
			(font
				(size 1.27 1.27)
			)
			(justify left bottom)
		)
	)
	(label "ETH_CONN_SH"
		(at 245.11 265.43 0)
		(effects
			(font
				(size 1.27 1.27)
			)
			(justify left bottom)
		)
	)
	(label "GBE_RGMII.RXD0"
		(at 25.4 63.5 0)
		(effects
			(font
				(size 1.27 1.27)
			)
			(justify left bottom)
		)
	)
	(label "GBE_RGMII.GTX_CLK"
		(at 153.67 83.82 0)
		(effects
			(font
				(size 1.27 1.27)
			)
			(justify left bottom)
		)
	)
	(label "GBE2_N"
		(at 232.41 76.2 180)
		(effects
			(font
				(size 1.27 1.27)
			)
			(justify right bottom)
		)
	)
	(label "ETH_RMII.RXER"
		(at 55.88 205.74 0)
		(effects
			(font
				(size 1.27 1.27)
			)
			(justify left bottom)
		)
	)
	(label "HDMI.D1_P"
		(at 323.85 171.45 0)
		(effects
			(font
				(size 1.27 1.27)
			)
			(justify left bottom)
		)
	)
	(label "HDMI.D2_N"
		(at 323.85 168.91 0)
		(effects
			(font
				(size 1.27 1.27)
			)
			(justify left bottom)
		)
	)
	(label "GBE_LED_LINK+"
		(at 378.46 99.695 0)
		(effects
			(font
				(size 1.27 1.27)
			)
			(justify left bottom)
		)
	)
	(label "GBE2_N"
		(at 331.47 105.41 0)
		(effects
			(font
				(size 1.27 1.27)
			)
			(justify left bottom)
		)
	)
	(label "ETH_PHY_RXD1"
		(at 25.4 229.87 0)
		(effects
			(font
				(size 1.27 1.27)
			)
			(justify left bottom)
		)
	)
	(label "HDMI.D0_N"
		(at 323.85 179.07 0)
		(effects
			(font
				(size 1.27 1.27)
			)
			(justify left bottom)
		)
	)
	(label "HDMI_CONN_5V"
		(at 358.14 217.17 0)
		(effects
			(font
				(size 1.27 1.27)
			)
			(justify left bottom)
		)
	)
	(label "HDMI.D2_P"
		(at 323.85 166.37 0)
		(effects
			(font
				(size 1.27 1.27)
			)
			(justify left bottom)
		)
	)
	(label "GBE3_N"
		(at 331.47 100.33 0)
		(effects
			(font
				(size 1.27 1.27)
			)
			(justify left bottom)
		)
	)
	(label "GBE_RGMII.GTR_CLK"
		(at 153.67 101.6 0)
		(effects
			(font
				(size 1.27 1.27)
			)
			(justify left bottom)
		)
	)
	(hierarchical_label "POE_ETH{POE}"
		(shape output)
		(at 196.85 274.32 180)
		(effects
			(font
				(size 1.27 1.27)
			)
			(justify right)
		)
	)
	(hierarchical_label "POE_GBE{POE}"
		(shape output)
		(at 331.47 134.62 180)
		(effects
			(font
				(size 1.27 1.27)
			)
			(justify right)
		)
	)
	(hierarchical_label "ETH_RMII{RMII}"
		(shape bidirectional)
		(at 40.64 195.58 180)
		(effects
			(font
				(size 1.27 1.27)
			)
			(justify right)
		)
	)
	(hierarchical_label "GBE_RGMII{RGMII}"
		(shape bidirectional)
		(at 134.62 87.63 180)
		(effects
			(font
				(size 1.27 1.27)
			)
			(justify right)
		)
	)
	(hierarchical_label "HDMI{HDMI}"
		(shape bidirectional)
		(at 309.88 187.96 180)
		(effects
			(font
				(size 1.27 1.27)
			)
			(justify right)
		)
	)
	(symbol
		(lib_id "antmicroResistors0402:R_10k_0402")
		(at 52.07 229.87 0)
		(mirror x)
		(unit 1)
		(exclude_from_sim no)
		(in_bom yes)
		(on_board yes)
		(dnp no)
		(property "Reference" "R220"
			(at 59.69 228.6 0)
			(effects
				(font
					(size 1.27 1.27)
				)
			)
		)
		(property "Value" "R_10k_0402"
			(at 72.39 217.17 0)
			(effects
				(font
					(size 1.27 1.27)
					(thickness 0.15)
				)
				(justify left bottom)
				(hide yes)
			)
		)
		(property "Footprint" "antmicro-footprints:R_0402_1005Metric"
			(at 72.39 214.63 0)
			(effects
				(font
					(size 1.27 1.27)
					(thickness 0.15)
				)
				(justify left bottom)
				(hide yes)
			)
		)
		(property "Datasheet" "https://www.bourns.com/docs/product-datasheets/cr.pdf"
			(at 72.39 212.09 0)
			(effects
				(font
					(size 1.27 1.27)
					(thickness 0.15)
				)
				(justify left bottom)
				(hide yes)
			)
		)
		(property "Description" ""
			(at 52.07 229.87 0)
			(effects
				(font
					(size 1.27 1.27)
				)
			)
		)
		(property "Manufacturer" "Bourns"
			(at 72.39 207.01 0)
			(effects
				(font
					(size 1.27 1.27)
					(thickness 0.15)
				)
				(justify left bottom)
				(hide yes)
			)
		)
		(property "MPN" "CR0402-FX-1002GLF"
			(at 72.39 209.55 0)
			(effects
				(font
					(size 1.27 1.27)
					(thickness 0.15)
				)
				(justify left bottom)
				(hide yes)
			)
		)
		(property "Val" "10k"
			(at 50.165 228.6 0)
			(effects
				(font
					(size 1.27 1.27)
					(thickness 0.15)
				)
			)
		)
		(property "License" "Apache-2.0"
			(at 72.39 204.47 0)
			(effects
				(font
					(size 1.27 1.27)
					(thickness 0.15)
				)
				(justify left bottom)
				(hide yes)
			)
		)
		(property "Author" "Antmicro"
			(at 72.39 201.93 0)
			(effects
				(font
					(size 1.27 1.27)
					(thickness 0.15)
				)
				(justify left bottom)
				(hide yes)
			)
		)
		(property "Tolerance" "1%"
			(at 72.39 219.71 0)
			(effects
				(font
					(size 1.27 1.27)
				)
				(justify left bottom)
				(hide yes)
			)
		)
		(pin "1"
		)
		(pin "2"
		)
		(instances
			(project "k410t-devboard"
				(path ""
					(reference "R220")
					(unit 1)
				)
			)
		)
	)
	(symbol
		(lib_id "antmicroResistors0402:R_0R_0402")
		(at 342.9 171.45 0)
		(unit 1)
		(exclude_from_sim no)
		(in_bom yes)
		(on_board yes)
		(dnp no)
		(property "Reference" "R256"
			(at 350.52 170.18 0)
			(effects
				(font
					(size 1.27 1.27)
				)
			)
		)
		(property "Value" "R_0R_0402"
			(at 363.22 184.15 0)
			(effects
				(font
					(size 1.27 1.27)
					(thickness 0.15)
				)
				(justify left bottom)
				(hide yes)
			)
		)
		(property "Footprint" "antmicro-footprints:R_0402_1005Metric"
			(at 363.22 186.69 0)
			(effects
				(font
					(size 1.27 1.27)
					(thickness 0.15)
				)
				(justify left bottom)
				(hide yes)
			)
		)
		(property "Datasheet" "https://industrial.panasonic.com/cdbs/www-data/pdf/RDA0000/AOA0000C301.pdf"
			(at 363.22 189.23 0)
			(effects
				(font
					(size 1.27 1.27)
					(thickness 0.15)
				)
				(justify left bottom)
				(hide yes)
			)
		)
		(property "Description" ""
			(at 342.9 171.45 0)
			(effects
				(font
					(size 1.27 1.27)
				)
			)
		)
		(property "Manufacturer" "Panasonic"
			(at 363.22 194.31 0)
			(effects
				(font
					(size 1.27 1.27)
					(thickness 0.15)
				)
				(justify left bottom)
				(hide yes)
			)
		)
		(property "MPN" "ERJ2GE0R00X"
			(at 363.22 191.77 0)
			(effects
				(font
					(size 1.27 1.27)
					(thickness 0.15)
				)
				(justify left bottom)
				(hide yes)
			)
		)
		(property "Val" "0R"
			(at 341.63 170.18 0)
			(effects
				(font
					(size 1.27 1.27)
					(thickness 0.15)
				)
			)
		)
		(property "License" "Apache-2.0"
			(at 363.22 196.85 0)
			(effects
				(font
					(size 1.27 1.27)
					(thickness 0.15)
				)
				(justify left bottom)
				(hide yes)
			)
		)
		(property "Author" "Antmicro"
			(at 363.22 199.39 0)
			(effects
				(font
					(size 1.27 1.27)
					(thickness 0.15)
				)
				(justify left bottom)
				(hide yes)
			)
		)
		(property "Tolerance" "~"
			(at 363.22 181.61 0)
			(effects
				(font
					(size 1.27 1.27)
				)
				(justify left bottom)
				(hide yes)
			)
		)
		(property "Current" "1A"
			(at 363.22 201.93 0)
			(effects
				(font
					(size 1.27 1.27)
					(thickness 0.15)
				)
				(justify left bottom)
				(hide yes)
			)
		)
		(pin "1"
		)
		(pin "2"
		)
		(instances
			(project "k410t-devboard"
				(path ""
					(reference "R256")
					(unit 1)
				)
			)
		)
	)
	(symbol
		(lib_id "antmicroResistors0402:R_2k2_0402")
		(at 52.07 114.3 0)
		(unit 1)
		(exclude_from_sim no)
		(in_bom no)
		(on_board yes)
		(dnp yes)
		(property "Reference" "R218"
			(at 59.69 113.03 0)
			(effects
				(font
					(size 1.27 1.27)
				)
			)
		)
		(property "Value" "R_2k2_0402"
			(at 72.39 127 0)
			(effects
				(font
					(size 1.27 1.27)
					(thickness 0.15)
				)
				(justify left bottom)
				(hide yes)
			)
		)
		(property "Footprint" "antmicro-footprints:R_0402_1005Metric"
			(at 72.39 129.54 0)
			(effects
				(font
					(size 1.27 1.27)
					(thickness 0.15)
				)
				(justify left bottom)
				(hide yes)
			)
		)
		(property "Datasheet" "https://www.bourns.com/docs/product-datasheets/cr.pdf"
			(at 72.39 132.08 0)
			(effects
				(font
					(size 1.27 1.27)
					(thickness 0.15)
				)
				(justify left bottom)
				(hide yes)
			)
		)
		(property "Description" ""
			(at 52.07 114.3 0)
			(effects
				(font
					(size 1.27 1.27)
				)
			)
		)
		(property "Manufacturer" "Bourns"
			(at 72.39 137.16 0)
			(effects
				(font
					(size 1.27 1.27)
					(thickness 0.15)
				)
				(justify left bottom)
				(hide yes)
			)
		)
		(property "MPN" "CR0402-FX-2201GLF"
			(at 72.39 134.62 0)
			(effects
				(font
					(size 1.27 1.27)
					(thickness 0.15)
				)
				(justify left bottom)
				(hide yes)
			)
		)
		(property "Val" "2k2"
			(at 50.165 113.03 0)
			(effects
				(font
					(size 1.27 1.27)
					(thickness 0.15)
				)
			)
		)
		(property "DNP" "DNP"
			(at 54.61 114.3 0)
			(effects
				(font
					(size 1.27 1.27)
				)
			)
		)
		(property "License" "Apache-2.0"
			(at 72.39 139.7 0)
			(effects
				(font
					(size 1.27 1.27)
					(thickness 0.15)
				)
				(justify left bottom)
				(hide yes)
			)
		)
		(property "Author" "Antmicro"
			(at 72.39 142.24 0)
			(effects
				(font
					(size 1.27 1.27)
					(thickness 0.15)
				)
				(justify left bottom)
				(hide yes)
			)
		)
		(property "Tolerance" "1%"
			(at 72.39 124.46 0)
			(effects
				(font
					(size 1.27 1.27)
				)
				(justify left bottom)
				(hide yes)
			)
		)
		(pin "1"
		)
		(pin "2"
		)
		(instances
			(project "k410t-devboard"
				(path ""
					(reference "R218")
					(unit 1)
				)
			)
		)
	)
	(symbol
		(lib_id "antmicroCapacitors0402:C_10p_0402")
		(at 246.38 205.74 90)
		(unit 1)
		(exclude_from_sim no)
		(in_bom yes)
		(on_board yes)
		(dnp no)
		(fields_autoplaced yes)
		(property "Reference" "C279"
			(at 248.92 201.9235 90)
			(effects
				(font
					(size 1.27 1.27)
				)
				(justify right)
			)
		)
		(property "Value" "C_10p_0402"
			(at 256.54 185.42 0)
			(effects
				(font
					(size 1.27 1.27)
					(thickness 0.15)
				)
				(justify left bottom)
				(hide yes)
			)
		)
		(property "Footprint" "antmicro-footprints:C_0402_1005Metric"
			(at 259.08 185.42 0)
			(effects
				(font
					(size 1.27 1.27)
					(thickness 0.15)
				)
				(justify left bottom)
				(hide yes)
			)
		)
		(property "Datasheet" "https://www.murata.com/products/productdetail?partno=GCM1555C1H100GA16%23"
			(at 261.62 185.42 0)
			(effects
				(font
					(size 1.27 1.27)
					(thickness 0.15)
				)
				(justify left bottom)
				(hide yes)
			)
		)
		(property "Description" ""
			(at 246.38 205.74 0)
			(effects
				(font
					(size 1.27 1.27)
				)
			)
		)
		(property "Manufacturer" "Murata"
			(at 266.7 185.42 0)
			(effects
				(font
					(size 1.27 1.27)
					(thickness 0.15)
				)
				(justify left bottom)
				(hide yes)
			)
		)
		(property "MPN" "GCM1555C1H100GA16D"
			(at 264.16 185.42 0)
			(effects
				(font
					(size 1.27 1.27)
					(thickness 0.15)
				)
				(justify left bottom)
				(hide yes)
			)
		)
		(property "Val" "10p"
			(at 248.92 204.4635 90)
			(effects
				(font
					(size 1.27 1.27)
					(thickness 0.15)
				)
				(justify right)
			)
		)
		(property "License" "Apache-2.0"
			(at 269.24 185.42 0)
			(effects
				(font
					(size 1.27 1.27)
					(thickness 0.15)
				)
				(justify left bottom)
				(hide yes)
			)
		)
		(property "Author" "Antmicro"
			(at 271.78 185.42 0)
			(effects
				(font
					(size 1.27 1.27)
					(thickness 0.15)
				)
				(justify left bottom)
				(hide yes)
			)
		)
		(property "Voltage" "50V"
			(at 274.32 185.42 0)
			(effects
				(font
					(size 1.27 1.27)
				)
				(justify left bottom)
				(hide yes)
			)
		)
		(property "Dielectric" "C0G"
			(at 276.86 185.42 0)
			(effects
				(font
					(size 1.27 1.27)
				)
				(justify left bottom)
				(hide yes)
			)
		)
		(pin "1"
		)
		(pin "2"
		)
		(instances
			(project "k410t-devboard"
				(path ""
					(reference "C279")
					(unit 1)
				)
			)
		)
	)
	(symbol
		(lib_id "antmicroResistors0402:R_10k_0402")
		(at 116.84 55.88 0)
		(unit 1)
		(exclude_from_sim no)
		(in_bom yes)
		(on_board yes)
		(dnp no)
		(property "Reference" "R239"
			(at 124.46 54.61 0)
			(effects
				(font
					(size 1.27 1.27)
				)
			)
		)
		(property "Value" "R_10k_0402"
			(at 137.16 68.58 0)
			(effects
				(font
					(size 1.27 1.27)
					(thickness 0.15)
				)
				(justify left bottom)
				(hide yes)
			)
		)
		(property "Footprint" "antmicro-footprints:R_0402_1005Metric"
			(at 137.16 71.12 0)
			(effects
				(font
					(size 1.27 1.27)
					(thickness 0.15)
				)
				(justify left bottom)
				(hide yes)
			)
		)
		(property "Datasheet" "https://www.bourns.com/docs/product-datasheets/cr.pdf"
			(at 137.16 73.66 0)
			(effects
				(font
					(size 1.27 1.27)
					(thickness 0.15)
				)
				(justify left bottom)
				(hide yes)
			)
		)
		(property "Description" ""
			(at 116.84 55.88 0)
			(effects
				(font
					(size 1.27 1.27)
				)
			)
		)
		(property "Manufacturer" "Bourns"
			(at 137.16 78.74 0)
			(effects
				(font
					(size 1.27 1.27)
					(thickness 0.15)
				)
				(justify left bottom)
				(hide yes)
			)
		)
		(property "MPN" "CR0402-FX-1002GLF"
			(at 137.16 76.2 0)
			(effects
				(font
					(size 1.27 1.27)
					(thickness 0.15)
				)
				(justify left bottom)
				(hide yes)
			)
		)
		(property "Val" "10k"
			(at 114.935 54.61 0)
			(effects
				(font
					(size 1.27 1.27)
					(thickness 0.15)
				)
			)
		)
		(property "License" "Apache-2.0"
			(at 137.16 81.28 0)
			(effects
				(font
					(size 1.27 1.27)
					(thickness 0.15)
				)
				(justify left bottom)
				(hide yes)
			)
		)
		(property "Author" "Antmicro"
			(at 137.16 83.82 0)
			(effects
				(font
					(size 1.27 1.27)
					(thickness 0.15)
				)
				(justify left bottom)
				(hide yes)
			)
		)
		(property "Tolerance" "1%"
			(at 137.16 66.04 0)
			(effects
				(font
					(size 1.27 1.27)
				)
				(justify left bottom)
				(hide yes)
			)
		)
		(pin "1"
		)
		(pin "2"
		)
		(instances
			(project "k410t-devboard"
				(path ""
					(reference "R239")
					(unit 1)
				)
			)
		)
	)
	(symbol
		(lib_id "antmicropower:+3.3V")
		(at 262.89 245.11 0)
		(unit 1)
		(exclude_from_sim no)
		(in_bom yes)
		(on_board yes)
		(dnp no)
		(property "Reference" "#PWR0299"
			(at 262.89 248.92 0)
			(effects
				(font
					(size 1.27 1.27)
				)
				(hide yes)
			)
		)
		(property "Value" "+3V3"
			(at 262.89 241.554 0)
			(effects
				(font
					(size 1.27 1.27)
				)
			)
		)
		(property "Footprint" ""
			(at 262.89 245.11 0)
			(effects
				(font
					(size 1.27 1.27)
				)
				(hide yes)
			)
		)
		(property "Datasheet" ""
			(at 262.89 245.11 0)
			(effects
				(font
					(size 1.27 1.27)
				)
				(hide yes)
			)
		)
		(property "Description" ""
			(at 262.89 245.11 0)
			(effects
				(font
					(size 1.27 1.27)
				)
			)
		)
		(pin "1"
		)
		(instances
			(project "k410t-devboard"
				(path ""
					(reference "#PWR0299")
					(unit 1)
				)
			)
		)
	)
	(symbol
		(lib_id "antmicroModularConnectorsJacksWithMagnetics:0895-2C1R-GVH")
		(at 351.79 95.25 0)
		(unit 2)
		(exclude_from_sim no)
		(in_bom yes)
		(on_board yes)
		(dnp no)
		(fields_autoplaced yes)
		(property "Reference" "J15"
			(at 365.5405 87.63 0)
			(effects
				(font
					(size 1.27 1.27)
				)
			)
		)
		(property "Value" "0895-2C1R-GVH"
			(at 365.76 90.805 0)
			(effects
				(font
					(size 1.27 1.27)
					(thickness 0.15)
				)
				(hide yes)
			)
		)
		(property "Footprint" "antmicro-footprints:0895-2C1R-GVH"
			(at 392.43 102.87 0)
			(effects
				(font
					(size 1.27 1.27)
					(thickness 0.15)
				)
				(justify left bottom)
				(hide yes)
			)
		)
		(property "Datasheet" "https://www.belfuse.com/resources/drawings/magneticsolutions/dr-mag-0895-2c1r-gvh.pdf"
			(at 392.43 105.41 0)
			(effects
				(font
					(size 1.27 1.27)
					(thickness 0.15)
				)
				(justify left bottom)
				(hide yes)
			)
		)
		(property "Description" ""
			(at 351.79 95.25 0)
			(effects
				(font
					(size 1.27 1.27)
				)
			)
		)
		(property "MPN" "0895-2C1R-GVH"
			(at 365.5405 90.17 0)
			(effects
				(font
					(size 1.27 1.27)
					(thickness 0.15)
				)
			)
		)
		(property "Manufacturer" "Bel Fuse"
			(at 392.43 110.49 0)
			(effects
				(font
					(size 1.27 1.27)
					(thickness 0.15)
				)
				(justify left bottom)
				(hide yes)
			)
		)
		(property "Author" "Antmicro"
			(at 392.43 113.03 0)
			(effects
				(font
					(size 1.27 1.27)
					(thickness 0.15)
				)
				(justify left bottom)
				(hide yes)
			)
		)
		(property "License" "Apache-2.0"
			(at 392.43 115.57 0)
			(effects
				(font
					(size 1.27 1.27)
					(thickness 0.15)
				)
				(justify left bottom)
				(hide yes)
			)
		)
		(pin "10_2"
		)
		(pin "11_2"
		)
		(pin "12_2"
		)
		(pin "13_2"
		)
		(pin "14_2"
		)
		(pin "15_2"
		)
		(pin "16_2"
		)
		(pin "17_2"
		)
		(pin "18_2"
		)
		(pin "1_2"
		)
		(pin "2_2"
		)
		(pin "3_2"
		)
		(pin "4_2"
		)
		(pin "5_2"
		)
		(pin "6_2"
		)
		(pin "7_2"
		)
		(pin "8_2"
		)
		(pin "9_2"
		)
		(pin "10_1"
		)
		(pin "11_1"
		)
		(pin "12_1"
		)
		(pin "13_1"
		)
		(pin "14_1"
		)
		(pin "15_1"
		)
		(pin "16_1"
		)
		(pin "17_1"
		)
		(pin "18_1"
		)
		(pin "1_1"
		)
		(pin "2_1"
		)
		(pin "3_1"
		)
		(pin "4_1"
		)
		(pin "5_1"
		)
		(pin "6_1"
		)
		(pin "7_1"
		)
		(pin "8_1"
		)
		(pin "9_1"
		)
		(pin "SH"
		)
		(pin "SH"
		)
		(pin "SH"
		)
		(pin "SH"
		)
		(pin "SH"
		)
		(pin "SH"
		)
		(instances
			(project "k410t-devboard"
				(path ""
					(reference "J15")
					(unit 2)
				)
			)
		)
	)
	(symbol
		(lib_id "antmicroResistors0402:R_0R_0402")
		(at 342.9 184.15 0)
		(unit 1)
		(exclude_from_sim no)
		(in_bom yes)
		(on_board yes)
		(dnp no)
		(property "Reference" "R261"
			(at 350.52 182.88 0)
			(effects
				(font
					(size 1.27 1.27)
				)
			)
		)
		(property "Value" "R_0R_0402"
			(at 363.22 196.85 0)
			(effects
				(font
					(size 1.27 1.27)
					(thickness 0.15)
				)
				(justify left bottom)
				(hide yes)
			)
		)
		(property "Footprint" "antmicro-footprints:R_0402_1005Metric"
			(at 363.22 199.39 0)
			(effects
				(font
					(size 1.27 1.27)
					(thickness 0.15)
				)
				(justify left bottom)
				(hide yes)
			)
		)
		(property "Datasheet" "https://industrial.panasonic.com/cdbs/www-data/pdf/RDA0000/AOA0000C301.pdf"
			(at 363.22 201.93 0)
			(effects
				(font
					(size 1.27 1.27)
					(thickness 0.15)
				)
				(justify left bottom)
				(hide yes)
			)
		)
		(property "Description" ""
			(at 342.9 184.15 0)
			(effects
				(font
					(size 1.27 1.27)
				)
			)
		)
		(property "Manufacturer" "Panasonic"
			(at 363.22 207.01 0)
			(effects
				(font
					(size 1.27 1.27)
					(thickness 0.15)
				)
				(justify left bottom)
				(hide yes)
			)
		)
		(property "MPN" "ERJ2GE0R00X"
			(at 363.22 204.47 0)
			(effects
				(font
					(size 1.27 1.27)
					(thickness 0.15)
				)
				(justify left bottom)
				(hide yes)
			)
		)
		(property "Val" "0R"
			(at 341.63 182.88 0)
			(effects
				(font
					(size 1.27 1.27)
					(thickness 0.15)
				)
			)
		)
		(property "License" "Apache-2.0"
			(at 363.22 209.55 0)
			(effects
				(font
					(size 1.27 1.27)
					(thickness 0.15)
				)
				(justify left bottom)
				(hide yes)
			)
		)
		(property "Author" "Antmicro"
			(at 363.22 212.09 0)
			(effects
				(font
					(size 1.27 1.27)
					(thickness 0.15)
				)
				(justify left bottom)
				(hide yes)
			)
		)
		(property "Tolerance" "~"
			(at 363.22 194.31 0)
			(effects
				(font
					(size 1.27 1.27)
				)
				(justify left bottom)
				(hide yes)
			)
		)
		(property "Current" "1A"
			(at 363.22 214.63 0)
			(effects
				(font
					(size 1.27 1.27)
					(thickness 0.15)
				)
				(justify left bottom)
				(hide yes)
			)
		)
		(pin "1"
		)
		(pin "2"
		)
		(instances
			(project "k410t-devboard"
				(path ""
					(reference "R261")
					(unit 1)
				)
			)
		)
	)
	(symbol
		(lib_id "antmicropower:PWR_FLAG")
		(at 328.295 157.48 0)
		(unit 1)
		(exclude_from_sim no)
		(in_bom yes)
		(on_board yes)
		(dnp no)
		(fields_autoplaced yes)
		(property "Reference" "#FLG013"
			(at 328.295 155.575 0)
			(effects
				(font
					(size 1.27 1.27)
				)
				(hide yes)
			)
		)
		(property "Value" "PWR_FLAG"
			(at 328.295 153.67 0)
			(effects
				(font
					(size 1.27 1.27)
				)
			)
		)
		(property "Footprint" ""
			(at 328.295 157.48 0)
			(effects
				(font
					(size 1.27 1.27)
				)
				(hide yes)
			)
		)
		(property "Datasheet" ""
			(at 328.295 157.48 0)
			(effects
				(font
					(size 1.27 1.27)
				)
				(hide yes)
			)
		)
		(property "Description" ""
			(at 328.295 157.48 0)
			(effects
				(font
					(size 1.27 1.27)
				)
			)
		)
		(pin "1"
		)
		(instances
			(project "k410t-devboard"
				(path ""
					(reference "#FLG013")
					(unit 1)
				)
			)
		)
	)
	(symbol
		(lib_id "antmicroInterfaceControllers:LAN8720A-CP-TR-ABC")
		(at 137.16 167.64 0)
		(unit 1)
		(exclude_from_sim no)
		(in_bom yes)
		(on_board yes)
		(dnp no)
		(fields_autoplaced yes)
		(property "Reference" "U26"
			(at 156.21 160.02 0)
			(effects
				(font
					(size 1.27 1.27)
				)
			)
		)
		(property "Value" "LAN8720A-CP-TR-ABC"
			(at 156.21 162.56 0)
			(effects
				(font
					(size 1.27 1.27)
					(thickness 0.15)
				)
				(hide yes)
			)
		)
		(property "Footprint" "antmicro-footprints:QFN-24-1EP_4x4mm_P0.5mm_EP2.6x2.6mm"
			(at 190.5 175.26 0)
			(effects
				(font
					(size 1.27 1.27)
					(thickness 0.15)
				)
				(justify left bottom)
				(hide yes)
			)
		)
		(property "Datasheet" "http://ww1.microchip.com/downloads/en/DeviceDoc/8720a.pdf"
			(at 190.5 177.8 0)
			(effects
				(font
					(size 1.27 1.27)
					(thickness 0.15)
				)
				(justify left bottom)
				(hide yes)
			)
		)
		(property "Description" ""
			(at 137.16 167.64 0)
			(effects
				(font
					(size 1.27 1.27)
				)
			)
		)
		(property "MPN" "LAN8720A-CP-TR-ABC"
			(at 156.21 162.56 0)
			(effects
				(font
					(size 1.27 1.27)
					(thickness 0.15)
				)
			)
		)
		(property "Manufacturer" "Microchip Technology"
			(at 190.5 182.88 0)
			(effects
				(font
					(size 1.27 1.27)
					(thickness 0.15)
				)
				(justify left bottom)
				(hide yes)
			)
		)
		(property "Author" "Antmicro"
			(at 190.5 185.42 0)
			(effects
				(font
					(size 1.27 1.27)
					(thickness 0.15)
				)
				(justify left bottom)
				(hide yes)
			)
		)
		(property "License" "Apache-2.0"
			(at 190.5 187.96 0)
			(effects
				(font
					(size 1.27 1.27)
					(thickness 0.15)
				)
				(justify left bottom)
				(hide yes)
			)
		)
		(pin "1"
		)
		(pin "10"
		)
		(pin "11"
		)
		(pin "12"
		)
		(pin "13"
		)
		(pin "14"
		)
		(pin "15"
		)
		(pin "16"
		)
		(pin "17"
		)
		(pin "18"
		)
		(pin "19"
		)
		(pin "2"
		)
		(pin "20"
		)
		(pin "21"
		)
		(pin "22"
		)
		(pin "23"
		)
		(pin "24"
		)
		(pin "25"
		)
		(pin "3"
		)
		(pin "4"
		)
		(pin "5"
		)
		(pin "6"
		)
		(pin "7"
		)
		(pin "8"
		)
		(pin "9"
		)
		(instances
			(project "k410t-devboard"
				(path ""
					(reference "U26")
					(unit 1)
				)
			)
		)
	)
	(symbol
		(lib_id "antmicroResistors0402:R_2k2_0402")
		(at 52.07 267.97 0)
		(unit 1)
		(exclude_from_sim no)
		(in_bom yes)
		(on_board yes)
		(dnp no)
		(property "Reference" "R230"
			(at 59.69 266.7 0)
			(effects
				(font
					(size 1.27 1.27)
				)
			)
		)
		(property "Value" "R_2k2_0402"
			(at 72.39 280.67 0)
			(effects
				(font
					(size 1.27 1.27)
					(thickness 0.15)
				)
				(justify left bottom)
				(hide yes)
			)
		)
		(property "Footprint" "antmicro-footprints:R_0402_1005Metric"
			(at 72.39 283.21 0)
			(effects
				(font
					(size 1.27 1.27)
					(thickness 0.15)
				)
				(justify left bottom)
				(hide yes)
			)
		)
		(property "Datasheet" "https://www.bourns.com/docs/product-datasheets/cr.pdf"
			(at 72.39 285.75 0)
			(effects
				(font
					(size 1.27 1.27)
					(thickness 0.15)
				)
				(justify left bottom)
				(hide yes)
			)
		)
		(property "Description" ""
			(at 52.07 267.97 0)
			(effects
				(font
					(size 1.27 1.27)
				)
			)
		)
		(property "Manufacturer" "Bourns"
			(at 72.39 290.83 0)
			(effects
				(font
					(size 1.27 1.27)
					(thickness 0.15)
				)
				(justify left bottom)
				(hide yes)
			)
		)
		(property "MPN" "CR0402-FX-2201GLF"
			(at 72.39 288.29 0)
			(effects
				(font
					(size 1.27 1.27)
					(thickness 0.15)
				)
				(justify left bottom)
				(hide yes)
			)
		)
		(property "Val" "2k2"
			(at 50.165 266.7 0)
			(effects
				(font
					(size 1.27 1.27)
					(thickness 0.15)
				)
			)
		)
		(property "License" "Apache-2.0"
			(at 72.39 293.37 0)
			(effects
				(font
					(size 1.27 1.27)
					(thickness 0.15)
				)
				(justify left bottom)
				(hide yes)
			)
		)
		(property "Author" "Antmicro"
			(at 72.39 295.91 0)
			(effects
				(font
					(size 1.27 1.27)
					(thickness 0.15)
				)
				(justify left bottom)
				(hide yes)
			)
		)
		(property "Tolerance" "1%"
			(at 72.39 278.13 0)
			(effects
				(font
					(size 1.27 1.27)
				)
				(justify left bottom)
				(hide yes)
			)
		)
		(pin "1"
		)
		(pin "2"
		)
		(instances
			(project "k410t-devboard"
				(path ""
					(reference "R230")
					(unit 1)
				)
			)
		)
	)
	(symbol
		(lib_id "antmicropower:GND")
		(at 116.84 163.83 0)
		(unit 1)
		(exclude_from_sim no)
		(in_bom yes)
		(on_board yes)
		(dnp no)
		(property "Reference" "#PWR0287"
			(at 116.84 170.18 0)
			(effects
				(font
					(size 1.27 1.27)
				)
				(hide yes)
			)
		)
		(property "Value" "GND"
			(at 116.84 167.64 0)
			(effects
				(font
					(size 1.27 1.27)
				)
			)
		)
		(property "Footprint" ""
			(at 125.73 171.45 0)
			(effects
				(font
					(size 1.27 1.27)
					(thickness 0.15)
				)
				(justify left bottom)
				(hide yes)
			)
		)
		(property "Datasheet" ""
			(at 125.73 176.53 0)
			(effects
				(font
					(size 1.27 1.27)
					(thickness 0.15)
				)
				(justify left bottom)
				(hide yes)
			)
		)
		(property "Description" ""
			(at 116.84 163.83 0)
			(effects
				(font
					(size 1.27 1.27)
				)
			)
		)
		(property "Author" "Antmicro"
			(at 125.73 171.45 0)
			(effects
				(font
					(size 1.27 1.27)
					(thickness 0.15)
				)
				(justify left bottom)
				(hide yes)
			)
		)
		(property "License" "Apache-2.0"
			(at 125.73 173.99 0)
			(effects
				(font
					(size 1.27 1.27)
					(thickness 0.15)
				)
				(justify left bottom)
				(hide yes)
			)
		)
		(pin "1"
		)
		(instances
			(project "k410t-devboard"
				(path ""
					(reference "#PWR0287")
					(unit 1)
				)
			)
		)
	)
	(symbol
		(lib_id "antmicroCapacitors0402:C_100n_0402")
		(at 237.49 26.67 90)
		(unit 1)
		(exclude_from_sim no)
		(in_bom yes)
		(on_board yes)
		(dnp no)
		(property "Reference" "C277"
			(at 238.125 22.225 90)
			(effects
				(font
					(size 1.27 1.27)
				)
				(justify right)
			)
		)
		(property "Value" "C_100n_0402"
			(at 247.65 6.35 0)
			(effects
				(font
					(size 1.27 1.27)
					(thickness 0.15)
				)
				(justify left bottom)
				(hide yes)
			)
		)
		(property "Footprint" "antmicro-footprints:C_0402_1005Metric"
			(at 250.19 6.35 0)
			(effects
				(font
					(size 1.27 1.27)
					(thickness 0.15)
				)
				(justify left bottom)
				(hide yes)
			)
		)
		(property "Datasheet" "https://www.murata.com/products/productdetail?partno=GRM155R61H104KE14%23"
			(at 252.73 6.35 0)
			(effects
				(font
					(size 1.27 1.27)
					(thickness 0.15)
				)
				(justify left bottom)
				(hide yes)
			)
		)
		(property "Description" ""
			(at 237.49 26.67 0)
			(effects
				(font
					(size 1.27 1.27)
				)
			)
		)
		(property "Manufacturer" "Murata"
			(at 257.81 6.35 0)
			(effects
				(font
					(size 1.27 1.27)
					(thickness 0.15)
				)
				(justify left bottom)
				(hide yes)
			)
		)
		(property "MPN" "GRM155R61H104KE14D"
			(at 255.27 6.35 0)
			(effects
				(font
					(size 1.27 1.27)
					(thickness 0.15)
				)
				(justify left bottom)
				(hide yes)
			)
		)
		(property "Val" "100n"
			(at 238.125 26.035 90)
			(effects
				(font
					(size 1.27 1.27)
					(thickness 0.15)
				)
				(justify right)
			)
		)
		(property "License" "Apache-2.0"
			(at 260.35 6.35 0)
			(effects
				(font
					(size 1.27 1.27)
					(thickness 0.15)
				)
				(justify left bottom)
				(hide yes)
			)
		)
		(property "Author" "Antmicro"
			(at 262.89 6.35 0)
			(effects
				(font
					(size 1.27 1.27)
					(thickness 0.15)
				)
				(justify left bottom)
				(hide yes)
			)
		)
		(property "Voltage" "50V"
			(at 265.43 6.35 0)
			(effects
				(font
					(size 1.27 1.27)
				)
				(justify left bottom)
				(hide yes)
			)
		)
		(property "Dielectric" "X5R"
			(at 267.97 6.35 0)
			(effects
				(font
					(size 1.27 1.27)
				)
				(justify left bottom)
				(hide yes)
			)
		)
		(pin "1"
		)
		(pin "2"
		)
		(instances
			(project "k410t-devboard"
				(path ""
					(reference "C277")
					(unit 1)
				)
			)
		)
	)
	(symbol
		(lib_id "antmicropower:GND")
		(at 229.87 118.11 0)
		(unit 1)
		(exclude_from_sim no)
		(in_bom yes)
		(on_board yes)
		(dnp no)
		(fields_autoplaced yes)
		(property "Reference" "#PWR0319"
			(at 229.87 124.46 0)
			(effects
				(font
					(size 1.27 1.27)
				)
				(hide yes)
			)
		)
		(property "Value" "GND"
			(at 229.87 121.92 0)
			(effects
				(font
					(size 1.27 1.27)
				)
			)
		)
		(property "Footprint" ""
			(at 238.76 125.73 0)
			(effects
				(font
					(size 1.27 1.27)
					(thickness 0.15)
				)
				(justify left bottom)
				(hide yes)
			)
		)
		(property "Datasheet" ""
			(at 238.76 130.81 0)
			(effects
				(font
					(size 1.27 1.27)
					(thickness 0.15)
				)
				(justify left bottom)
				(hide yes)
			)
		)
		(property "Description" ""
			(at 229.87 118.11 0)
			(effects
				(font
					(size 1.27 1.27)
				)
			)
		)
		(property "Author" "Antmicro"
			(at 238.76 125.73 0)
			(effects
				(font
					(size 1.27 1.27)
					(thickness 0.15)
				)
				(justify left bottom)
				(hide yes)
			)
		)
		(property "License" "Apache-2.0"
			(at 238.76 128.27 0)
			(effects
				(font
					(size 1.27 1.27)
					(thickness 0.15)
				)
				(justify left bottom)
				(hide yes)
			)
		)
		(pin "1"
		)
		(instances
			(project "k410t-devboard"
				(path ""
					(reference "#PWR0319")
					(unit 1)
				)
			)
		)
	)
	(symbol
		(lib_id "antmicropower:GND")
		(at 280.67 44.45 0)
		(unit 1)
		(exclude_from_sim no)
		(in_bom yes)
		(on_board yes)
		(dnp no)
		(fields_autoplaced yes)
		(property "Reference" "#PWR0337"
			(at 280.67 50.8 0)
			(effects
				(font
					(size 1.27 1.27)
				)
				(hide yes)
			)
		)
		(property "Value" "GND"
			(at 280.67 48.26 0)
			(effects
				(font
					(size 1.27 1.27)
				)
			)
		)
		(property "Footprint" ""
			(at 289.56 52.07 0)
			(effects
				(font
					(size 1.27 1.27)
					(thickness 0.15)
				)
				(justify left bottom)
				(hide yes)
			)
		)
		(property "Datasheet" ""
			(at 289.56 57.15 0)
			(effects
				(font
					(size 1.27 1.27)
					(thickness 0.15)
				)
				(justify left bottom)
				(hide yes)
			)
		)
		(property "Description" ""
			(at 280.67 44.45 0)
			(effects
				(font
					(size 1.27 1.27)
				)
			)
		)
		(property "Author" "Antmicro"
			(at 289.56 52.07 0)
			(effects
				(font
					(size 1.27 1.27)
					(thickness 0.15)
				)
				(justify left bottom)
				(hide yes)
			)
		)
		(property "License" "Apache-2.0"
			(at 289.56 54.61 0)
			(effects
				(font
					(size 1.27 1.27)
					(thickness 0.15)
				)
				(justify left bottom)
				(hide yes)
			)
		)
		(pin "1"
		)
		(instances
			(project "k410t-devboard"
				(path ""
					(reference "#PWR0337")
					(unit 1)
				)
			)
		)
	)
	(symbol
		(lib_id "antmicropower:GND")
		(at 142.24 29.21 0)
		(unit 1)
		(exclude_from_sim no)
		(in_bom yes)
		(on_board yes)
		(dnp no)
		(fields_autoplaced yes)
		(property "Reference" "#PWR0300"
			(at 142.24 35.56 0)
			(effects
				(font
					(size 1.27 1.27)
				)
				(hide yes)
			)
		)
		(property "Value" "GND"
			(at 142.24 33.02 0)
			(effects
				(font
					(size 1.27 1.27)
				)
			)
		)
		(property "Footprint" ""
			(at 151.13 36.83 0)
			(effects
				(font
					(size 1.27 1.27)
					(thickness 0.15)
				)
				(justify left bottom)
				(hide yes)
			)
		)
		(property "Datasheet" ""
			(at 151.13 41.91 0)
			(effects
				(font
					(size 1.27 1.27)
					(thickness 0.15)
				)
				(justify left bottom)
				(hide yes)
			)
		)
		(property "Description" ""
			(at 142.24 29.21 0)
			(effects
				(font
					(size 1.27 1.27)
				)
			)
		)
		(property "Author" "Antmicro"
			(at 151.13 36.83 0)
			(effects
				(font
					(size 1.27 1.27)
					(thickness 0.15)
				)
				(justify left bottom)
				(hide yes)
			)
		)
		(property "License" "Apache-2.0"
			(at 151.13 39.37 0)
			(effects
				(font
					(size 1.27 1.27)
					(thickness 0.15)
				)
				(justify left bottom)
				(hide yes)
			)
		)
		(pin "1"
		)
		(instances
			(project "k410t-devboard"
				(path ""
					(reference "#PWR0300")
					(unit 1)
				)
			)
		)
	)
	(symbol
		(lib_id "antmicroCapacitors0402:C_10u_0402")
		(at 116.84 162.56 90)
		(unit 1)
		(exclude_from_sim no)
		(in_bom yes)
		(on_board yes)
		(dnp no)
		(property "Reference" "C253"
			(at 117.475 158.115 90)
			(effects
				(font
					(size 1.27 1.27)
				)
				(justify right)
			)
		)
		(property "Value" "C_10u_0402"
			(at 127 142.24 0)
			(effects
				(font
					(size 1.27 1.27)
					(thickness 0.15)
				)
				(justify left bottom)
				(hide yes)
			)
		)
		(property "Footprint" "antmicro-footprints:C_0402_1005Metric"
			(at 129.54 142.24 0)
			(effects
				(font
					(size 1.27 1.27)
					(thickness 0.15)
				)
				(justify left bottom)
				(hide yes)
			)
		)
		(property "Datasheet" "https://www.yageo.com/en/Chart/Download/pdf/CC0402MRX5R5BB106"
			(at 132.08 142.24 0)
			(effects
				(font
					(size 1.27 1.27)
					(thickness 0.15)
				)
				(justify left bottom)
				(hide yes)
			)
		)
		(property "Description" ""
			(at 116.84 162.56 0)
			(effects
				(font
					(size 1.27 1.27)
				)
			)
		)
		(property "Manufacturer" "YAGEO"
			(at 137.16 142.24 0)
			(effects
				(font
					(size 1.27 1.27)
					(thickness 0.15)
				)
				(justify left bottom)
				(hide yes)
			)
		)
		(property "MPN" "CC0402MRX5R5BB106"
			(at 134.62 142.24 0)
			(effects
				(font
					(size 1.27 1.27)
					(thickness 0.15)
				)
				(justify left bottom)
				(hide yes)
			)
		)
		(property "Val" "10u"
			(at 117.475 161.925 90)
			(effects
				(font
					(size 1.27 1.27)
					(thickness 0.15)
				)
				(justify right)
			)
		)
		(property "License" "Apache-2.0"
			(at 139.7 142.24 0)
			(effects
				(font
					(size 1.27 1.27)
					(thickness 0.15)
				)
				(justify left bottom)
				(hide yes)
			)
		)
		(property "Author" "Antmicro"
			(at 142.24 142.24 0)
			(effects
				(font
					(size 1.27 1.27)
					(thickness 0.15)
				)
				(justify left bottom)
				(hide yes)
			)
		)
		(property "Voltage" ""
			(at 144.78 142.24 0)
			(effects
				(font
					(size 1.27 1.27)
				)
				(justify left bottom)
				(hide yes)
			)
		)
		(property "Dielectric" ""
			(at 147.32 142.24 0)
			(effects
				(font
					(size 1.27 1.27)
				)
				(justify left bottom)
				(hide yes)
			)
		)
		(pin "1"
		)
		(pin "2"
		)
		(instances
			(project "k410t-devboard"
				(path ""
					(reference "C253")
					(unit 1)
				)
			)
		)
	)
	(symbol
		(lib_id "antmicroResistors0402:R_10k_0402")
		(at 52.07 74.93 0)
		(unit 1)
		(exclude_from_sim no)
		(in_bom yes)
		(on_board yes)
		(dnp no)
		(property "Reference" "R206"
			(at 59.69 73.66 0)
			(effects
				(font
					(size 1.27 1.27)
				)
			)
		)
		(property "Value" "R_10k_0402"
			(at 72.39 87.63 0)
			(effects
				(font
					(size 1.27 1.27)
					(thickness 0.15)
				)
				(justify left bottom)
				(hide yes)
			)
		)
		(property "Footprint" "antmicro-footprints:R_0402_1005Metric"
			(at 72.39 90.17 0)
			(effects
				(font
					(size 1.27 1.27)
					(thickness 0.15)
				)
				(justify left bottom)
				(hide yes)
			)
		)
		(property "Datasheet" "https://www.bourns.com/docs/product-datasheets/cr.pdf"
			(at 72.39 92.71 0)
			(effects
				(font
					(size 1.27 1.27)
					(thickness 0.15)
				)
				(justify left bottom)
				(hide yes)
			)
		)
		(property "Description" ""
			(at 52.07 74.93 0)
			(effects
				(font
					(size 1.27 1.27)
				)
			)
		)
		(property "Manufacturer" "Bourns"
			(at 72.39 97.79 0)
			(effects
				(font
					(size 1.27 1.27)
					(thickness 0.15)
				)
				(justify left bottom)
				(hide yes)
			)
		)
		(property "MPN" "CR0402-FX-1002GLF"
			(at 72.39 95.25 0)
			(effects
				(font
					(size 1.27 1.27)
					(thickness 0.15)
				)
				(justify left bottom)
				(hide yes)
			)
		)
		(property "Val" "10k"
			(at 50.165 73.66 0)
			(effects
				(font
					(size 1.27 1.27)
					(thickness 0.15)
				)
			)
		)
		(property "License" "Apache-2.0"
			(at 72.39 100.33 0)
			(effects
				(font
					(size 1.27 1.27)
					(thickness 0.15)
				)
				(justify left bottom)
				(hide yes)
			)
		)
		(property "Author" "Antmicro"
			(at 72.39 102.87 0)
			(effects
				(font
					(size 1.27 1.27)
					(thickness 0.15)
				)
				(justify left bottom)
				(hide yes)
			)
		)
		(property "Tolerance" "1%"
			(at 72.39 85.09 0)
			(effects
				(font
					(size 1.27 1.27)
				)
				(justify left bottom)
				(hide yes)
			)
		)
		(pin "1"
		)
		(pin "2"
		)
		(instances
			(project "k410t-devboard"
				(path ""
					(reference "R206")
					(unit 1)
				)
			)
		)
	)
	(symbol
		(lib_id "antmicroResistors0402:R_0R_0402")
		(at 342.9 181.61 0)
		(unit 1)
		(exclude_from_sim no)
		(in_bom yes)
		(on_board yes)
		(dnp no)
		(property "Reference" "R260"
			(at 350.52 180.34 0)
			(effects
				(font
					(size 1.27 1.27)
				)
			)
		)
		(property "Value" "R_0R_0402"
			(at 363.22 194.31 0)
			(effects
				(font
					(size 1.27 1.27)
					(thickness 0.15)
				)
				(justify left bottom)
				(hide yes)
			)
		)
		(property "Footprint" "antmicro-footprints:R_0402_1005Metric"
			(at 363.22 196.85 0)
			(effects
				(font
					(size 1.27 1.27)
					(thickness 0.15)
				)
				(justify left bottom)
				(hide yes)
			)
		)
		(property "Datasheet" "https://industrial.panasonic.com/cdbs/www-data/pdf/RDA0000/AOA0000C301.pdf"
			(at 363.22 199.39 0)
			(effects
				(font
					(size 1.27 1.27)
					(thickness 0.15)
				)
				(justify left bottom)
				(hide yes)
			)
		)
		(property "Description" ""
			(at 342.9 181.61 0)
			(effects
				(font
					(size 1.27 1.27)
				)
			)
		)
		(property "Manufacturer" "Panasonic"
			(at 363.22 204.47 0)
			(effects
				(font
					(size 1.27 1.27)
					(thickness 0.15)
				)
				(justify left bottom)
				(hide yes)
			)
		)
		(property "MPN" "ERJ2GE0R00X"
			(at 363.22 201.93 0)
			(effects
				(font
					(size 1.27 1.27)
					(thickness 0.15)
				)
				(justify left bottom)
				(hide yes)
			)
		)
		(property "Val" "0R"
			(at 341.63 180.34 0)
			(effects
				(font
					(size 1.27 1.27)
					(thickness 0.15)
				)
			)
		)
		(property "License" "Apache-2.0"
			(at 363.22 207.01 0)
			(effects
				(font
					(size 1.27 1.27)
					(thickness 0.15)
				)
				(justify left bottom)
				(hide yes)
			)
		)
		(property "Author" "Antmicro"
			(at 363.22 209.55 0)
			(effects
				(font
					(size 1.27 1.27)
					(thickness 0.15)
				)
				(justify left bottom)
				(hide yes)
			)
		)
		(property "Tolerance" "~"
			(at 363.22 191.77 0)
			(effects
				(font
					(size 1.27 1.27)
				)
				(justify left bottom)
				(hide yes)
			)
		)
		(property "Current" "1A"
			(at 363.22 212.09 0)
			(effects
				(font
					(size 1.27 1.27)
					(thickness 0.15)
				)
				(justify left bottom)
				(hide yes)
			)
		)
		(pin "1"
		)
		(pin "2"
		)
		(instances
			(project "k410t-devboard"
				(path ""
					(reference "R260")
					(unit 1)
				)
			)
		)
	)
	(symbol
		(lib_id "antmicropower:GND")
		(at 223.52 118.11 0)
		(unit 1)
		(exclude_from_sim no)
		(in_bom yes)
		(on_board yes)
		(dnp no)
		(fields_autoplaced yes)
		(property "Reference" "#PWR0318"
			(at 223.52 124.46 0)
			(effects
				(font
					(size 1.27 1.27)
				)
				(hide yes)
			)
		)
		(property "Value" "GND"
			(at 223.52 121.92 0)
			(effects
				(font
					(size 1.27 1.27)
				)
			)
		)
		(property "Footprint" ""
			(at 232.41 125.73 0)
			(effects
				(font
					(size 1.27 1.27)
					(thickness 0.15)
				)
				(justify left bottom)
				(hide yes)
			)
		)
		(property "Datasheet" ""
			(at 232.41 130.81 0)
			(effects
				(font
					(size 1.27 1.27)
					(thickness 0.15)
				)
				(justify left bottom)
				(hide yes)
			)
		)
		(property "Description" ""
			(at 223.52 118.11 0)
			(effects
				(font
					(size 1.27 1.27)
				)
			)
		)
		(property "Author" "Antmicro"
			(at 232.41 125.73 0)
			(effects
				(font
					(size 1.27 1.27)
					(thickness 0.15)
				)
				(justify left bottom)
				(hide yes)
			)
		)
		(property "License" "Apache-2.0"
			(at 232.41 128.27 0)
			(effects
				(font
					(size 1.27 1.27)
					(thickness 0.15)
				)
				(justify left bottom)
				(hide yes)
			)
		)
		(pin "1"
		)
		(instances
			(project "k410t-devboard"
				(path ""
					(reference "#PWR0318")
					(unit 1)
				)
			)
		)
	)
	(symbol
		(lib_id "antmicroCapacitors0402:C_100n_0402")
		(at 142.24 26.67 90)
		(unit 1)
		(exclude_from_sim no)
		(in_bom yes)
		(on_board yes)
		(dnp no)
		(fields_autoplaced yes)
		(property "Reference" "C261"
			(at 145.415 22.8535 90)
			(effects
				(font
					(size 1.27 1.27)
				)
				(justify right)
			)
		)
		(property "Value" "C_100n_0402"
			(at 152.4 6.35 0)
			(effects
				(font
					(size 1.27 1.27)
					(thickness 0.15)
				)
				(justify left bottom)
				(hide yes)
			)
		)
		(property "Footprint" "antmicro-footprints:C_0402_1005Metric"
			(at 154.94 6.35 0)
			(effects
				(font
					(size 1.27 1.27)
					(thickness 0.15)
				)
				(justify left bottom)
				(hide yes)
			)
		)
		(property "Datasheet" "https://www.murata.com/products/productdetail?partno=GRM155R61H104KE14%23"
			(at 157.48 6.35 0)
			(effects
				(font
					(size 1.27 1.27)
					(thickness 0.15)
				)
				(justify left bottom)
				(hide yes)
			)
		)
		(property "Description" ""
			(at 142.24 26.67 0)
			(effects
				(font
					(size 1.27 1.27)
				)
			)
		)
		(property "Manufacturer" "Murata"
			(at 162.56 6.35 0)
			(effects
				(font
					(size 1.27 1.27)
					(thickness 0.15)
				)
				(justify left bottom)
				(hide yes)
			)
		)
		(property "MPN" "GRM155R61H104KE14D"
			(at 160.02 6.35 0)
			(effects
				(font
					(size 1.27 1.27)
					(thickness 0.15)
				)
				(justify left bottom)
				(hide yes)
			)
		)
		(property "Val" "100n"
			(at 145.415 25.3935 90)
			(effects
				(font
					(size 1.27 1.27)
					(thickness 0.15)
				)
				(justify right)
			)
		)
		(property "License" "Apache-2.0"
			(at 165.1 6.35 0)
			(effects
				(font
					(size 1.27 1.27)
					(thickness 0.15)
				)
				(justify left bottom)
				(hide yes)
			)
		)
		(property "Author" "Antmicro"
			(at 167.64 6.35 0)
			(effects
				(font
					(size 1.27 1.27)
					(thickness 0.15)
				)
				(justify left bottom)
				(hide yes)
			)
		)
		(property "Voltage" "50V"
			(at 170.18 6.35 0)
			(effects
				(font
					(size 1.27 1.27)
				)
				(justify left bottom)
				(hide yes)
			)
		)
		(property "Dielectric" "X5R"
			(at 172.72 6.35 0)
			(effects
				(font
					(size 1.27 1.27)
				)
				(justify left bottom)
				(hide yes)
			)
		)
		(pin "1"
		)
		(pin "2"
		)
		(instances
			(project "k410t-devboard"
				(path ""
					(reference "C261")
					(unit 1)
				)
			)
		)
	)
	(symbol
		(lib_id "antmicropower:GND")
		(at 309.88 240.03 0)
		(unit 1)
		(exclude_from_sim no)
		(in_bom yes)
		(on_board yes)
		(dnp no)
		(property "Reference" "#PWR0343"
			(at 309.88 246.38 0)
			(effects
				(font
					(size 1.27 1.27)
				)
				(hide yes)
			)
		)
		(property "Value" "GND"
			(at 309.88 243.84 0)
			(effects
				(font
					(size 1.27 1.27)
				)
			)
		)
		(property "Footprint" ""
			(at 318.77 247.65 0)
			(effects
				(font
					(size 1.27 1.27)
					(thickness 0.15)
				)
				(justify left bottom)
				(hide yes)
			)
		)
		(property "Datasheet" ""
			(at 318.77 252.73 0)
			(effects
				(font
					(size 1.27 1.27)
					(thickness 0.15)
				)
				(justify left bottom)
				(hide yes)
			)
		)
		(property "Description" ""
			(at 309.88 240.03 0)
			(effects
				(font
					(size 1.27 1.27)
				)
			)
		)
		(property "Author" "Antmicro"
			(at 318.77 247.65 0)
			(effects
				(font
					(size 1.27 1.27)
					(thickness 0.15)
				)
				(justify left bottom)
				(hide yes)
			)
		)
		(property "License" "Apache-2.0"
			(at 318.77 250.19 0)
			(effects
				(font
					(size 1.27 1.27)
					(thickness 0.15)
				)
				(justify left bottom)
				(hide yes)
			)
		)
		(pin "1"
		)
		(instances
			(project "k410t-devboard"
				(path ""
					(reference "#PWR0343")
					(unit 1)
				)
			)
		)
	)
	(symbol
		(lib_id "antmicroResistors0402:R_0R_0402")
		(at 342.9 176.53 0)
		(unit 1)
		(exclude_from_sim no)
		(in_bom yes)
		(on_board yes)
		(dnp no)
		(property "Reference" "R258"
			(at 350.52 175.26 0)
			(effects
				(font
					(size 1.27 1.27)
				)
			)
		)
		(property "Value" "R_0R_0402"
			(at 363.22 189.23 0)
			(effects
				(font
					(size 1.27 1.27)
					(thickness 0.15)
				)
				(justify left bottom)
				(hide yes)
			)
		)
		(property "Footprint" "antmicro-footprints:R_0402_1005Metric"
			(at 363.22 191.77 0)
			(effects
				(font
					(size 1.27 1.27)
					(thickness 0.15)
				)
				(justify left bottom)
				(hide yes)
			)
		)
		(property "Datasheet" "https://industrial.panasonic.com/cdbs/www-data/pdf/RDA0000/AOA0000C301.pdf"
			(at 363.22 194.31 0)
			(effects
				(font
					(size 1.27 1.27)
					(thickness 0.15)
				)
				(justify left bottom)
				(hide yes)
			)
		)
		(property "Description" ""
			(at 342.9 176.53 0)
			(effects
				(font
					(size 1.27 1.27)
				)
			)
		)
		(property "Manufacturer" "Panasonic"
			(at 363.22 199.39 0)
			(effects
				(font
					(size 1.27 1.27)
					(thickness 0.15)
				)
				(justify left bottom)
				(hide yes)
			)
		)
		(property "MPN" "ERJ2GE0R00X"
			(at 363.22 196.85 0)
			(effects
				(font
					(size 1.27 1.27)
					(thickness 0.15)
				)
				(justify left bottom)
				(hide yes)
			)
		)
		(property "Val" "0R"
			(at 341.63 175.26 0)
			(effects
				(font
					(size 1.27 1.27)
					(thickness 0.15)
				)
			)
		)
		(property "License" "Apache-2.0"
			(at 363.22 201.93 0)
			(effects
				(font
					(size 1.27 1.27)
					(thickness 0.15)
				)
				(justify left bottom)
				(hide yes)
			)
		)
		(property "Author" "Antmicro"
			(at 363.22 204.47 0)
			(effects
				(font
					(size 1.27 1.27)
					(thickness 0.15)
				)
				(justify left bottom)
				(hide yes)
			)
		)
		(property "Tolerance" "~"
			(at 363.22 186.69 0)
			(effects
				(font
					(size 1.27 1.27)
				)
				(justify left bottom)
				(hide yes)
			)
		)
		(property "Current" "1A"
			(at 363.22 207.01 0)
			(effects
				(font
					(size 1.27 1.27)
					(thickness 0.15)
				)
				(justify left bottom)
				(hide yes)
			)
		)
		(pin "1"
		)
		(pin "2"
		)
		(instances
			(project "k410t-devboard"
				(path ""
					(reference "R258")
					(unit 1)
				)
			)
		)
	)
	(symbol
		(lib_id "antmicroResistors0402:R_10k_0402")
		(at 52.07 60.96 0)
		(mirror x)
		(unit 1)
		(exclude_from_sim no)
		(in_bom no)
		(on_board yes)
		(dnp yes)
		(property "Reference" "R201"
			(at 59.69 59.69 0)
			(effects
				(font
					(size 1.27 1.27)
				)
			)
		)
		(property "Value" "R_10k_0402"
			(at 72.39 48.26 0)
			(effects
				(font
					(size 1.27 1.27)
					(thickness 0.15)
				)
				(justify left bottom)
				(hide yes)
			)
		)
		(property "Footprint" "antmicro-footprints:R_0402_1005Metric"
			(at 72.39 45.72 0)
			(effects
				(font
					(size 1.27 1.27)
					(thickness 0.15)
				)
				(justify left bottom)
				(hide yes)
			)
		)
		(property "Datasheet" "https://www.bourns.com/docs/product-datasheets/cr.pdf"
			(at 72.39 43.18 0)
			(effects
				(font
					(size 1.27 1.27)
					(thickness 0.15)
				)
				(justify left bottom)
				(hide yes)
			)
		)
		(property "Description" ""
			(at 52.07 60.96 0)
			(effects
				(font
					(size 1.27 1.27)
				)
			)
		)
		(property "Manufacturer" "Bourns"
			(at 72.39 38.1 0)
			(effects
				(font
					(size 1.27 1.27)
					(thickness 0.15)
				)
				(justify left bottom)
				(hide yes)
			)
		)
		(property "MPN" "CR0402-FX-1002GLF"
			(at 72.39 40.64 0)
			(effects
				(font
					(size 1.27 1.27)
					(thickness 0.15)
				)
				(justify left bottom)
				(hide yes)
			)
		)
		(property "Val" "10k"
			(at 50.165 59.69 0)
			(effects
				(font
					(size 1.27 1.27)
					(thickness 0.15)
				)
			)
		)
		(property "DNP" "DNP"
			(at 54.61 60.96 0)
			(effects
				(font
					(size 1.27 1.27)
				)
			)
		)
		(property "License" "Apache-2.0"
			(at 72.39 35.56 0)
			(effects
				(font
					(size 1.27 1.27)
					(thickness 0.15)
				)
				(justify left bottom)
				(hide yes)
			)
		)
		(property "Author" "Antmicro"
			(at 72.39 33.02 0)
			(effects
				(font
					(size 1.27 1.27)
					(thickness 0.15)
				)
				(justify left bottom)
				(hide yes)
			)
		)
		(property "Tolerance" "1%"
			(at 72.39 50.8 0)
			(effects
				(font
					(size 1.27 1.27)
				)
				(justify left bottom)
				(hide yes)
			)
		)
		(pin "1"
		)
		(pin "2"
		)
		(instances
			(project "k410t-devboard"
				(path ""
					(reference "R201")
					(unit 1)
				)
			)
		)
	)
	(symbol
		(lib_id "antmicroCapacitors0402:C_100n_0402")
		(at 247.65 26.67 90)
		(unit 1)
		(exclude_from_sim no)
		(in_bom yes)
		(on_board yes)
		(dnp no)
		(property "Reference" "C281"
			(at 248.285 22.225 90)
			(effects
				(font
					(size 1.27 1.27)
				)
				(justify right)
			)
		)
		(property "Value" "C_100n_0402"
			(at 257.81 6.35 0)
			(effects
				(font
					(size 1.27 1.27)
					(thickness 0.15)
				)
				(justify left bottom)
				(hide yes)
			)
		)
		(property "Footprint" "antmicro-footprints:C_0402_1005Metric"
			(at 260.35 6.35 0)
			(effects
				(font
					(size 1.27 1.27)
					(thickness 0.15)
				)
				(justify left bottom)
				(hide yes)
			)
		)
		(property "Datasheet" "https://www.murata.com/products/productdetail?partno=GRM155R61H104KE14%23"
			(at 262.89 6.35 0)
			(effects
				(font
					(size 1.27 1.27)
					(thickness 0.15)
				)
				(justify left bottom)
				(hide yes)
			)
		)
		(property "Description" ""
			(at 247.65 26.67 0)
			(effects
				(font
					(size 1.27 1.27)
				)
			)
		)
		(property "Manufacturer" "Murata"
			(at 267.97 6.35 0)
			(effects
				(font
					(size 1.27 1.27)
					(thickness 0.15)
				)
				(justify left bottom)
				(hide yes)
			)
		)
		(property "MPN" "GRM155R61H104KE14D"
			(at 265.43 6.35 0)
			(effects
				(font
					(size 1.27 1.27)
					(thickness 0.15)
				)
				(justify left bottom)
				(hide yes)
			)
		)
		(property "Val" "100n"
			(at 248.285 26.035 90)
			(effects
				(font
					(size 1.27 1.27)
					(thickness 0.15)
				)
				(justify right)
			)
		)
		(property "License" "Apache-2.0"
			(at 270.51 6.35 0)
			(effects
				(font
					(size 1.27 1.27)
					(thickness 0.15)
				)
				(justify left bottom)
				(hide yes)
			)
		)
		(property "Author" "Antmicro"
			(at 273.05 6.35 0)
			(effects
				(font
					(size 1.27 1.27)
					(thickness 0.15)
				)
				(justify left bottom)
				(hide yes)
			)
		)
		(property "Voltage" "50V"
			(at 275.59 6.35 0)
			(effects
				(font
					(size 1.27 1.27)
				)
				(justify left bottom)
				(hide yes)
			)
		)
		(property "Dielectric" "X5R"
			(at 278.13 6.35 0)
			(effects
				(font
					(size 1.27 1.27)
				)
				(justify left bottom)
				(hide yes)
			)
		)
		(pin "1"
		)
		(pin "2"
		)
		(instances
			(project "k410t-devboard"
				(path ""
					(reference "C281")
					(unit 1)
				)
			)
		)
	)
	(symbol
		(lib_id "antmicropower:+5V")
		(at 294.64 152.4 0)
		(unit 1)
		(exclude_from_sim no)
		(in_bom yes)
		(on_board yes)
		(dnp no)
		(property "Reference" "#PWR0306"
			(at 294.64 156.21 0)
			(effects
				(font
					(size 1.27 1.27)
				)
				(hide yes)
			)
		)
		(property "Value" "+5V"
			(at 294.64 148.844 0)
			(effects
				(font
					(size 1.27 1.27)
				)
			)
		)
		(property "Footprint" ""
			(at 294.64 152.4 0)
			(effects
				(font
					(size 1.27 1.27)
				)
				(hide yes)
			)
		)
		(property "Datasheet" ""
			(at 294.64 152.4 0)
			(effects
				(font
					(size 1.27 1.27)
				)
				(hide yes)
			)
		)
		(property "Description" ""
			(at 294.64 152.4 0)
			(effects
				(font
					(size 1.27 1.27)
				)
			)
		)
		(property "Author" "Antmicro"
			(at 309.88 160.02 0)
			(effects
				(font
					(size 1.27 1.27)
					(thickness 0.15)
				)
				(justify left bottom)
				(hide yes)
			)
		)
		(property "License" "Apache-2.0"
			(at 309.88 162.56 0)
			(effects
				(font
					(size 1.27 1.27)
					(thickness 0.15)
				)
				(justify left bottom)
				(hide yes)
			)
		)
		(pin "1"
		)
		(instances
			(project "k410t-devboard"
				(path ""
					(reference "#PWR0306")
					(unit 1)
				)
			)
		)
	)
	(symbol
		(lib_id "antmicroResistors0402:R_10k_0402")
		(at 52.07 72.39 0)
		(mirror x)
		(unit 1)
		(exclude_from_sim no)
		(in_bom yes)
		(on_board yes)
		(dnp no)
		(property "Reference" "R205"
			(at 59.69 71.12 0)
			(effects
				(font
					(size 1.27 1.27)
				)
			)
		)
		(property "Value" "R_10k_0402"
			(at 72.39 59.69 0)
			(effects
				(font
					(size 1.27 1.27)
					(thickness 0.15)
				)
				(justify left bottom)
				(hide yes)
			)
		)
		(property "Footprint" "antmicro-footprints:R_0402_1005Metric"
			(at 72.39 57.15 0)
			(effects
				(font
					(size 1.27 1.27)
					(thickness 0.15)
				)
				(justify left bottom)
				(hide yes)
			)
		)
		(property "Datasheet" "https://www.bourns.com/docs/product-datasheets/cr.pdf"
			(at 72.39 54.61 0)
			(effects
				(font
					(size 1.27 1.27)
					(thickness 0.15)
				)
				(justify left bottom)
				(hide yes)
			)
		)
		(property "Description" ""
			(at 52.07 72.39 0)
			(effects
				(font
					(size 1.27 1.27)
				)
			)
		)
		(property "Manufacturer" "Bourns"
			(at 72.39 49.53 0)
			(effects
				(font
					(size 1.27 1.27)
					(thickness 0.15)
				)
				(justify left bottom)
				(hide yes)
			)
		)
		(property "MPN" "CR0402-FX-1002GLF"
			(at 72.39 52.07 0)
			(effects
				(font
					(size 1.27 1.27)
					(thickness 0.15)
				)
				(justify left bottom)
				(hide yes)
			)
		)
		(property "Val" "10k"
			(at 50.165 71.12 0)
			(effects
				(font
					(size 1.27 1.27)
					(thickness 0.15)
				)
			)
		)
		(property "License" "Apache-2.0"
			(at 72.39 46.99 0)
			(effects
				(font
					(size 1.27 1.27)
					(thickness 0.15)
				)
				(justify left bottom)
				(hide yes)
			)
		)
		(property "Author" "Antmicro"
			(at 72.39 44.45 0)
			(effects
				(font
					(size 1.27 1.27)
					(thickness 0.15)
				)
				(justify left bottom)
				(hide yes)
			)
		)
		(property "Tolerance" "1%"
			(at 72.39 62.23 0)
			(effects
				(font
					(size 1.27 1.27)
				)
				(justify left bottom)
				(hide yes)
			)
		)
		(pin "1"
		)
		(pin "2"
		)
		(instances
			(project "k410t-devboard"
				(path ""
					(reference "R205")
					(unit 1)
				)
			)
		)
	)
	(symbol
		(lib_id "antmicroResistors0402:R_10k_0402")
		(at 25.4 172.72 0)
		(unit 1)
		(exclude_from_sim no)
		(in_bom yes)
		(on_board yes)
		(dnp no)
		(property "Reference" "R197"
			(at 33.02 171.45 0)
			(effects
				(font
					(size 1.27 1.27)
				)
			)
		)
		(property "Value" "R_10k_0402"
			(at 45.72 185.42 0)
			(effects
				(font
					(size 1.27 1.27)
					(thickness 0.15)
				)
				(justify left bottom)
				(hide yes)
			)
		)
		(property "Footprint" "antmicro-footprints:R_0402_1005Metric"
			(at 45.72 187.96 0)
			(effects
				(font
					(size 1.27 1.27)
					(thickness 0.15)
				)
				(justify left bottom)
				(hide yes)
			)
		)
		(property "Datasheet" "https://www.bourns.com/docs/product-datasheets/cr.pdf"
			(at 45.72 190.5 0)
			(effects
				(font
					(size 1.27 1.27)
					(thickness 0.15)
				)
				(justify left bottom)
				(hide yes)
			)
		)
		(property "Description" ""
			(at 25.4 172.72 0)
			(effects
				(font
					(size 1.27 1.27)
				)
			)
		)
		(property "Manufacturer" "Bourns"
			(at 45.72 195.58 0)
			(effects
				(font
					(size 1.27 1.27)
					(thickness 0.15)
				)
				(justify left bottom)
				(hide yes)
			)
		)
		(property "MPN" "CR0402-FX-1002GLF"
			(at 45.72 193.04 0)
			(effects
				(font
					(size 1.27 1.27)
					(thickness 0.15)
				)
				(justify left bottom)
				(hide yes)
			)
		)
		(property "Val" "10k"
			(at 23.495 171.45 0)
			(effects
				(font
					(size 1.27 1.27)
					(thickness 0.15)
				)
			)
		)
		(property "License" "Apache-2.0"
			(at 45.72 198.12 0)
			(effects
				(font
					(size 1.27 1.27)
					(thickness 0.15)
				)
				(justify left bottom)
				(hide yes)
			)
		)
		(property "Author" "Antmicro"
			(at 45.72 200.66 0)
			(effects
				(font
					(size 1.27 1.27)
					(thickness 0.15)
				)
				(justify left bottom)
				(hide yes)
			)
		)
		(property "Tolerance" "1%"
			(at 45.72 182.88 0)
			(effects
				(font
					(size 1.27 1.27)
				)
				(justify left bottom)
				(hide yes)
			)
		)
		(pin "1"
		)
		(pin "2"
		)
		(instances
			(project "k410t-devboard"
				(path ""
					(reference "R197")
					(unit 1)
				)
			)
		)
	)
	(symbol
		(lib_id "antmicroResistors0402:R_10R_0402")
		(at 105.41 198.12 0)
		(unit 1)
		(exclude_from_sim no)
		(in_bom yes)
		(on_board yes)
		(dnp no)
		(property "Reference" "R235"
			(at 113.03 196.85 0)
			(effects
				(font
					(size 1.27 1.27)
				)
			)
		)
		(property "Value" "R_10R_0402"
			(at 125.73 210.82 0)
			(effects
				(font
					(size 1.27 1.27)
					(thickness 0.15)
				)
				(justify left bottom)
				(hide yes)
			)
		)
		(property "Footprint" "antmicro-footprints:R_0402_1005Metric"
			(at 125.73 213.36 0)
			(effects
				(font
					(size 1.27 1.27)
					(thickness 0.15)
				)
				(justify left bottom)
				(hide yes)
			)
		)
		(property "Datasheet" "https://www.bourns.com/docs/product-datasheets/cr.pdf"
			(at 125.73 215.9 0)
			(effects
				(font
					(size 1.27 1.27)
					(thickness 0.15)
				)
				(justify left bottom)
				(hide yes)
			)
		)
		(property "Description" ""
			(at 105.41 198.12 0)
			(effects
				(font
					(size 1.27 1.27)
				)
			)
		)
		(property "Manufacturer" "Bourns"
			(at 125.73 220.98 0)
			(effects
				(font
					(size 1.27 1.27)
					(thickness 0.15)
				)
				(justify left bottom)
				(hide yes)
			)
		)
		(property "MPN" "CR0402-FX-10R0GLF"
			(at 125.73 218.44 0)
			(effects
				(font
					(size 1.27 1.27)
					(thickness 0.15)
				)
				(justify left bottom)
				(hide yes)
			)
		)
		(property "Val" "10R"
			(at 103.505 196.85 0)
			(effects
				(font
					(size 1.27 1.27)
					(thickness 0.15)
				)
			)
		)
		(property "License" "Apache-2.0"
			(at 125.73 223.52 0)
			(effects
				(font
					(size 1.27 1.27)
					(thickness 0.15)
				)
				(justify left bottom)
				(hide yes)
			)
		)
		(property "Author" "Antmicro"
			(at 125.73 226.06 0)
			(effects
				(font
					(size 1.27 1.27)
					(thickness 0.15)
				)
				(justify left bottom)
				(hide yes)
			)
		)
		(property "Tolerance" "1%"
			(at 125.73 208.28 0)
			(effects
				(font
					(size 1.27 1.27)
				)
				(justify left bottom)
				(hide yes)
			)
		)
		(pin "1"
		)
		(pin "2"
		)
		(instances
			(project "k410t-devboard"
				(path ""
					(reference "R235")
					(unit 1)
				)
			)
		)
	)
	(symbol
		(lib_id "antmicroResistors0603:R_220R_0603")
		(at 396.24 111.76 90)
		(unit 1)
		(exclude_from_sim no)
		(in_bom yes)
		(on_board yes)
		(dnp no)
		(fields_autoplaced yes)
		(property "Reference" "R263"
			(at 398.78 107.9499 90)
			(effects
				(font
					(size 1.27 1.27)
				)
				(justify right)
			)
		)
		(property "Value" "R_220R_0603"
			(at 408.94 91.44 0)
			(effects
				(font
					(size 1.27 1.27)
					(thickness 0.15)
				)
				(justify left bottom)
				(hide yes)
			)
		)
		(property "Footprint" "antmicro-footprints:R_0603_1608Metric"
			(at 411.48 91.44 0)
			(effects
				(font
					(size 1.27 1.27)
					(thickness 0.15)
				)
				(justify left bottom)
				(hide yes)
			)
		)
		(property "Datasheet" "https://www.bourns.com/docs/product-datasheets/cr.pdf"
			(at 414.02 91.44 0)
			(effects
				(font
					(size 1.27 1.27)
					(thickness 0.15)
				)
				(justify left bottom)
				(hide yes)
			)
		)
		(property "Description" ""
			(at 396.24 111.76 0)
			(effects
				(font
					(size 1.27 1.27)
				)
			)
		)
		(property "Manufacturer" "Bourns"
			(at 419.1 91.44 0)
			(effects
				(font
					(size 1.27 1.27)
					(thickness 0.15)
				)
				(justify left bottom)
				(hide yes)
			)
		)
		(property "MPN" "CR0603-FX-2200ELF"
			(at 416.56 91.44 0)
			(effects
				(font
					(size 1.27 1.27)
					(thickness 0.15)
				)
				(justify left bottom)
				(hide yes)
			)
		)
		(property "Val" "220R"
			(at 398.78 110.4899 90)
			(effects
				(font
					(size 1.27 1.27)
					(thickness 0.15)
				)
				(justify right)
			)
		)
		(property "License" "Apache-2.0"
			(at 421.64 91.44 0)
			(effects
				(font
					(size 1.27 1.27)
					(thickness 0.15)
				)
				(justify left bottom)
				(hide yes)
			)
		)
		(property "Author" "Antmicro"
			(at 424.18 91.44 0)
			(effects
				(font
					(size 1.27 1.27)
					(thickness 0.15)
				)
				(justify left bottom)
				(hide yes)
			)
		)
		(property "Tolerance" "1%"
			(at 406.4 91.44 0)
			(effects
				(font
					(size 1.27 1.27)
				)
				(justify left bottom)
				(hide yes)
			)
		)
		(pin "1"
		)
		(pin "2"
		)
		(instances
			(project "k410t-devboard"
				(path ""
					(reference "R263")
					(unit 1)
				)
			)
		)
	)
	(symbol
		(lib_id "antmicropower:GND")
		(at 237.49 44.45 0)
		(unit 1)
		(exclude_from_sim no)
		(in_bom yes)
		(on_board yes)
		(dnp no)
		(fields_autoplaced yes)
		(property "Reference" "#PWR0321"
			(at 237.49 50.8 0)
			(effects
				(font
					(size 1.27 1.27)
				)
				(hide yes)
			)
		)
		(property "Value" "GND"
			(at 237.49 48.26 0)
			(effects
				(font
					(size 1.27 1.27)
				)
			)
		)
		(property "Footprint" ""
			(at 246.38 52.07 0)
			(effects
				(font
					(size 1.27 1.27)
					(thickness 0.15)
				)
				(justify left bottom)
				(hide yes)
			)
		)
		(property "Datasheet" ""
			(at 246.38 57.15 0)
			(effects
				(font
					(size 1.27 1.27)
					(thickness 0.15)
				)
				(justify left bottom)
				(hide yes)
			)
		)
		(property "Description" ""
			(at 237.49 44.45 0)
			(effects
				(font
					(size 1.27 1.27)
				)
			)
		)
		(property "Author" "Antmicro"
			(at 246.38 52.07 0)
			(effects
				(font
					(size 1.27 1.27)
					(thickness 0.15)
				)
				(justify left bottom)
				(hide yes)
			)
		)
		(property "License" "Apache-2.0"
			(at 246.38 54.61 0)
			(effects
				(font
					(size 1.27 1.27)
					(thickness 0.15)
				)
				(justify left bottom)
				(hide yes)
			)
		)
		(pin "1"
		)
		(instances
			(project "k410t-devboard"
				(path ""
					(reference "#PWR0321")
					(unit 1)
				)
			)
		)
	)
	(symbol
		(lib_id "antmicropower:GND")
		(at 130.81 44.45 0)
		(mirror y)
		(unit 1)
		(exclude_from_sim no)
		(in_bom yes)
		(on_board yes)
		(dnp no)
		(fields_autoplaced yes)
		(property "Reference" "#PWR0296"
			(at 130.81 50.8 0)
			(effects
				(font
					(size 1.27 1.27)
				)
				(hide yes)
			)
		)
		(property "Value" "GND"
			(at 130.81 48.26 0)
			(effects
				(font
					(size 1.27 1.27)
				)
			)
		)
		(property "Footprint" ""
			(at 121.92 52.07 0)
			(effects
				(font
					(size 1.27 1.27)
					(thickness 0.15)
				)
				(justify left bottom)
				(hide yes)
			)
		)
		(property "Datasheet" ""
			(at 121.92 57.15 0)
			(effects
				(font
					(size 1.27 1.27)
					(thickness 0.15)
				)
				(justify left bottom)
				(hide yes)
			)
		)
		(property "Description" ""
			(at 130.81 44.45 0)
			(effects
				(font
					(size 1.27 1.27)
				)
			)
		)
		(property "Author" "Antmicro"
			(at 121.92 52.07 0)
			(effects
				(font
					(size 1.27 1.27)
					(thickness 0.15)
				)
				(justify left bottom)
				(hide yes)
			)
		)
		(property "License" "Apache-2.0"
			(at 121.92 54.61 0)
			(effects
				(font
					(size 1.27 1.27)
					(thickness 0.15)
				)
				(justify left bottom)
				(hide yes)
			)
		)
		(pin "1"
		)
		(instances
			(project "k410t-devboard"
				(path ""
					(reference "#PWR0296")
					(unit 1)
				)
			)
		)
	)
	(symbol
		(lib_id "antmicroCapacitors0402:C_100n_0402")
		(at 250.19 273.05 90)
		(unit 1)
		(exclude_from_sim no)
		(in_bom yes)
		(on_board yes)
		(dnp no)
		(fields_autoplaced yes)
		(property "Reference" "C272"
			(at 252.73 269.2335 90)
			(effects
				(font
					(size 1.27 1.27)
				)
				(justify right)
			)
		)
		(property "Value" "C_100n_0402"
			(at 260.35 252.73 0)
			(effects
				(font
					(size 1.27 1.27)
					(thickness 0.15)
				)
				(justify left bottom)
				(hide yes)
			)
		)
		(property "Footprint" "antmicro-footprints:C_0402_1005Metric"
			(at 262.89 252.73 0)
			(effects
				(font
					(size 1.27 1.27)
					(thickness 0.15)
				)
				(justify left bottom)
				(hide yes)
			)
		)
		(property "Datasheet" "https://www.murata.com/products/productdetail?partno=GRM155R61H104KE14%23"
			(at 265.43 252.73 0)
			(effects
				(font
					(size 1.27 1.27)
					(thickness 0.15)
				)
				(justify left bottom)
				(hide yes)
			)
		)
		(property "Description" ""
			(at 250.19 273.05 0)
			(effects
				(font
					(size 1.27 1.27)
				)
			)
		)
		(property "Manufacturer" "Murata"
			(at 270.51 252.73 0)
			(effects
				(font
					(size 1.27 1.27)
					(thickness 0.15)
				)
				(justify left bottom)
				(hide yes)
			)
		)
		(property "MPN" "GRM155R61H104KE14D"
			(at 267.97 252.73 0)
			(effects
				(font
					(size 1.27 1.27)
					(thickness 0.15)
				)
				(justify left bottom)
				(hide yes)
			)
		)
		(property "Val" "100n"
			(at 252.73 271.7735 90)
			(effects
				(font
					(size 1.27 1.27)
					(thickness 0.15)
				)
				(justify right)
			)
		)
		(property "License" "Apache-2.0"
			(at 273.05 252.73 0)
			(effects
				(font
					(size 1.27 1.27)
					(thickness 0.15)
				)
				(justify left bottom)
				(hide yes)
			)
		)
		(property "Author" "Antmicro"
			(at 275.59 252.73 0)
			(effects
				(font
					(size 1.27 1.27)
					(thickness 0.15)
				)
				(justify left bottom)
				(hide yes)
			)
		)
		(property "Voltage" "50V"
			(at 278.13 252.73 0)
			(effects
				(font
					(size 1.27 1.27)
				)
				(justify left bottom)
				(hide yes)
			)
		)
		(property "Dielectric" "X5R"
			(at 280.67 252.73 0)
			(effects
				(font
					(size 1.27 1.27)
				)
				(justify left bottom)
				(hide yes)
			)
		)
		(pin "1"
		)
		(pin "2"
		)
		(instances
			(project "k410t-devboard"
				(path ""
					(reference "C272")
					(unit 1)
				)
			)
		)
	)
	(symbol
		(lib_id "antmicroCapacitors0402:C_100n_0402")
		(at 259.08 26.67 90)
		(unit 1)
		(exclude_from_sim no)
		(in_bom yes)
		(on_board yes)
		(dnp no)
		(property "Reference" "C284"
			(at 259.715 22.225 90)
			(effects
				(font
					(size 1.27 1.27)
				)
				(justify right)
			)
		)
		(property "Value" "C_100n_0402"
			(at 269.24 6.35 0)
			(effects
				(font
					(size 1.27 1.27)
					(thickness 0.15)
				)
				(justify left bottom)
				(hide yes)
			)
		)
		(property "Footprint" "antmicro-footprints:C_0402_1005Metric"
			(at 271.78 6.35 0)
			(effects
				(font
					(size 1.27 1.27)
					(thickness 0.15)
				)
				(justify left bottom)
				(hide yes)
			)
		)
		(property "Datasheet" "https://www.murata.com/products/productdetail?partno=GRM155R61H104KE14%23"
			(at 274.32 6.35 0)
			(effects
				(font
					(size 1.27 1.27)
					(thickness 0.15)
				)
				(justify left bottom)
				(hide yes)
			)
		)
		(property "Description" ""
			(at 259.08 26.67 0)
			(effects
				(font
					(size 1.27 1.27)
				)
			)
		)
		(property "Manufacturer" "Murata"
			(at 279.4 6.35 0)
			(effects
				(font
					(size 1.27 1.27)
					(thickness 0.15)
				)
				(justify left bottom)
				(hide yes)
			)
		)
		(property "MPN" "GRM155R61H104KE14D"
			(at 276.86 6.35 0)
			(effects
				(font
					(size 1.27 1.27)
					(thickness 0.15)
				)
				(justify left bottom)
				(hide yes)
			)
		)
		(property "Val" "100n"
			(at 259.715 26.035 90)
			(effects
				(font
					(size 1.27 1.27)
					(thickness 0.15)
				)
				(justify right)
			)
		)
		(property "License" "Apache-2.0"
			(at 281.94 6.35 0)
			(effects
				(font
					(size 1.27 1.27)
					(thickness 0.15)
				)
				(justify left bottom)
				(hide yes)
			)
		)
		(property "Author" "Antmicro"
			(at 284.48 6.35 0)
			(effects
				(font
					(size 1.27 1.27)
					(thickness 0.15)
				)
				(justify left bottom)
				(hide yes)
			)
		)
		(property "Voltage" "50V"
			(at 287.02 6.35 0)
			(effects
				(font
					(size 1.27 1.27)
				)
				(justify left bottom)
				(hide yes)
			)
		)
		(property "Dielectric" "X5R"
			(at 289.56 6.35 0)
			(effects
				(font
					(size 1.27 1.27)
				)
				(justify left bottom)
				(hide yes)
			)
		)
		(pin "1"
		)
		(pin "2"
		)
		(instances
			(project "k410t-devboard"
				(path ""
					(reference "C284")
					(unit 1)
				)
			)
		)
	)
	(symbol
		(lib_id "antmicropower:GND")
		(at 247.65 44.45 0)
		(unit 1)
		(exclude_from_sim no)
		(in_bom yes)
		(on_board yes)
		(dnp no)
		(fields_autoplaced yes)
		(property "Reference" "#PWR0325"
			(at 247.65 50.8 0)
			(effects
				(font
					(size 1.27 1.27)
				)
				(hide yes)
			)
		)
		(property "Value" "GND"
			(at 247.65 48.26 0)
			(effects
				(font
					(size 1.27 1.27)
				)
			)
		)
		(property "Footprint" ""
			(at 256.54 52.07 0)
			(effects
				(font
					(size 1.27 1.27)
					(thickness 0.15)
				)
				(justify left bottom)
				(hide yes)
			)
		)
		(property "Datasheet" ""
			(at 256.54 57.15 0)
			(effects
				(font
					(size 1.27 1.27)
					(thickness 0.15)
				)
				(justify left bottom)
				(hide yes)
			)
		)
		(property "Description" ""
			(at 247.65 44.45 0)
			(effects
				(font
					(size 1.27 1.27)
				)
			)
		)
		(property "Author" "Antmicro"
			(at 256.54 52.07 0)
			(effects
				(font
					(size 1.27 1.27)
					(thickness 0.15)
				)
				(justify left bottom)
				(hide yes)
			)
		)
		(property "License" "Apache-2.0"
			(at 256.54 54.61 0)
			(effects
				(font
					(size 1.27 1.27)
					(thickness 0.15)
				)
				(justify left bottom)
				(hide yes)
			)
		)
		(pin "1"
		)
		(instances
			(project "k410t-devboard"
				(path ""
					(reference "#PWR0325")
					(unit 1)
				)
			)
		)
	)
	(symbol
		(lib_id "antmicroCapacitors0402:C_100n_0402")
		(at 130.81 26.67 90)
		(unit 1)
		(exclude_from_sim no)
		(in_bom yes)
		(on_board yes)
		(dnp no)
		(fields_autoplaced yes)
		(property "Reference" "C259"
			(at 133.35 22.8535 90)
			(effects
				(font
					(size 1.27 1.27)
				)
				(justify right)
			)
		)
		(property "Value" "C_100n_0402"
			(at 140.97 6.35 0)
			(effects
				(font
					(size 1.27 1.27)
					(thickness 0.15)
				)
				(justify left bottom)
				(hide yes)
			)
		)
		(property "Footprint" "antmicro-footprints:C_0402_1005Metric"
			(at 143.51 6.35 0)
			(effects
				(font
					(size 1.27 1.27)
					(thickness 0.15)
				)
				(justify left bottom)
				(hide yes)
			)
		)
		(property "Datasheet" "https://www.murata.com/products/productdetail?partno=GRM155R61H104KE14%23"
			(at 146.05 6.35 0)
			(effects
				(font
					(size 1.27 1.27)
					(thickness 0.15)
				)
				(justify left bottom)
				(hide yes)
			)
		)
		(property "Description" ""
			(at 130.81 26.67 0)
			(effects
				(font
					(size 1.27 1.27)
				)
			)
		)
		(property "Manufacturer" "Murata"
			(at 151.13 6.35 0)
			(effects
				(font
					(size 1.27 1.27)
					(thickness 0.15)
				)
				(justify left bottom)
				(hide yes)
			)
		)
		(property "MPN" "GRM155R61H104KE14D"
			(at 148.59 6.35 0)
			(effects
				(font
					(size 1.27 1.27)
					(thickness 0.15)
				)
				(justify left bottom)
				(hide yes)
			)
		)
		(property "Val" "100n"
			(at 133.35 25.3935 90)
			(effects
				(font
					(size 1.27 1.27)
					(thickness 0.15)
				)
				(justify right)
			)
		)
		(property "License" "Apache-2.0"
			(at 153.67 6.35 0)
			(effects
				(font
					(size 1.27 1.27)
					(thickness 0.15)
				)
				(justify left bottom)
				(hide yes)
			)
		)
		(property "Author" "Antmicro"
			(at 156.21 6.35 0)
			(effects
				(font
					(size 1.27 1.27)
					(thickness 0.15)
				)
				(justify left bottom)
				(hide yes)
			)
		)
		(property "Voltage" "50V"
			(at 158.75 6.35 0)
			(effects
				(font
					(size 1.27 1.27)
				)
				(justify left bottom)
				(hide yes)
			)
		)
		(property "Dielectric" "X5R"
			(at 161.29 6.35 0)
			(effects
				(font
					(size 1.27 1.27)
				)
				(justify left bottom)
				(hide yes)
			)
		)
		(pin "1"
		)
		(pin "2"
		)
		(instances
			(project "k410t-devboard"
				(path ""
					(reference "C259")
					(unit 1)
				)
			)
		)
	)
	(symbol
		(lib_id "antmicroResistors0402:R_10k_0402")
		(at 52.07 232.41 0)
		(mirror x)
		(unit 1)
		(exclude_from_sim no)
		(in_bom yes)
		(on_board yes)
		(dnp no)
		(property "Reference" "R221"
			(at 59.69 231.14 0)
			(effects
				(font
					(size 1.27 1.27)
				)
			)
		)
		(property "Value" "R_10k_0402"
			(at 72.39 219.71 0)
			(effects
				(font
					(size 1.27 1.27)
					(thickness 0.15)
				)
				(justify left bottom)
				(hide yes)
			)
		)
		(property "Footprint" "antmicro-footprints:R_0402_1005Metric"
			(at 72.39 217.17 0)
			(effects
				(font
					(size 1.27 1.27)
					(thickness 0.15)
				)
				(justify left bottom)
				(hide yes)
			)
		)
		(property "Datasheet" "https://www.bourns.com/docs/product-datasheets/cr.pdf"
			(at 72.39 214.63 0)
			(effects
				(font
					(size 1.27 1.27)
					(thickness 0.15)
				)
				(justify left bottom)
				(hide yes)
			)
		)
		(property "Description" ""
			(at 52.07 232.41 0)
			(effects
				(font
					(size 1.27 1.27)
				)
			)
		)
		(property "Manufacturer" "Bourns"
			(at 72.39 209.55 0)
			(effects
				(font
					(size 1.27 1.27)
					(thickness 0.15)
				)
				(justify left bottom)
				(hide yes)
			)
		)
		(property "MPN" "CR0402-FX-1002GLF"
			(at 72.39 212.09 0)
			(effects
				(font
					(size 1.27 1.27)
					(thickness 0.15)
				)
				(justify left bottom)
				(hide yes)
			)
		)
		(property "Val" "10k"
			(at 50.165 231.14 0)
			(effects
				(font
					(size 1.27 1.27)
					(thickness 0.15)
				)
			)
		)
		(property "License" "Apache-2.0"
			(at 72.39 207.01 0)
			(effects
				(font
					(size 1.27 1.27)
					(thickness 0.15)
				)
				(justify left bottom)
				(hide yes)
			)
		)
		(property "Author" "Antmicro"
			(at 72.39 204.47 0)
			(effects
				(font
					(size 1.27 1.27)
					(thickness 0.15)
				)
				(justify left bottom)
				(hide yes)
			)
		)
		(property "Tolerance" "1%"
			(at 72.39 222.25 0)
			(effects
				(font
					(size 1.27 1.27)
				)
				(justify left bottom)
				(hide yes)
			)
		)
		(pin "1"
		)
		(pin "2"
		)
		(instances
			(project "k410t-devboard"
				(path ""
					(reference "R221")
					(unit 1)
				)
			)
		)
	)
	(symbol
		(lib_id "antmicropower:GND")
		(at 406.4 222.25 0)
		(unit 1)
		(exclude_from_sim no)
		(in_bom yes)
		(on_board yes)
		(dnp no)
		(property "Reference" "#PWR0346"
			(at 406.4 228.6 0)
			(effects
				(font
					(size 1.27 1.27)
				)
				(hide yes)
			)
		)
		(property "Value" "GND"
			(at 405.13 226.06 0)
			(effects
				(font
					(size 1.27 1.27)
				)
			)
		)
		(property "Footprint" ""
			(at 415.29 229.87 0)
			(effects
				(font
					(size 1.27 1.27)
					(thickness 0.15)
				)
				(justify left bottom)
				(hide yes)
			)
		)
		(property "Datasheet" ""
			(at 415.29 234.95 0)
			(effects
				(font
					(size 1.27 1.27)
					(thickness 0.15)
				)
				(justify left bottom)
				(hide yes)
			)
		)
		(property "Description" ""
			(at 406.4 222.25 0)
			(effects
				(font
					(size 1.27 1.27)
				)
			)
		)
		(property "Author" "Antmicro"
			(at 415.29 229.87 0)
			(effects
				(font
					(size 1.27 1.27)
					(thickness 0.15)
				)
				(justify left bottom)
				(hide yes)
			)
		)
		(property "License" "Apache-2.0"
			(at 415.29 232.41 0)
			(effects
				(font
					(size 1.27 1.27)
					(thickness 0.15)
				)
				(justify left bottom)
				(hide yes)
			)
		)
		(pin "1"
		)
		(instances
			(project "k410t-devboard"
				(path ""
					(reference "#PWR0346")
					(unit 1)
				)
			)
		)
	)
	(symbol
		(lib_id "antmicropower:GND")
		(at 269.24 44.45 0)
		(unit 1)
		(exclude_from_sim no)
		(in_bom yes)
		(on_board yes)
		(dnp no)
		(fields_autoplaced yes)
		(property "Reference" "#PWR0335"
			(at 269.24 50.8 0)
			(effects
				(font
					(size 1.27 1.27)
				)
				(hide yes)
			)
		)
		(property "Value" "GND"
			(at 269.24 48.26 0)
			(effects
				(font
					(size 1.27 1.27)
				)
			)
		)
		(property "Footprint" ""
			(at 278.13 52.07 0)
			(effects
				(font
					(size 1.27 1.27)
					(thickness 0.15)
				)
				(justify left bottom)
				(hide yes)
			)
		)
		(property "Datasheet" ""
			(at 278.13 57.15 0)
			(effects
				(font
					(size 1.27 1.27)
					(thickness 0.15)
				)
				(justify left bottom)
				(hide yes)
			)
		)
		(property "Description" ""
			(at 269.24 44.45 0)
			(effects
				(font
					(size 1.27 1.27)
				)
			)
		)
		(property "Author" "Antmicro"
			(at 278.13 52.07 0)
			(effects
				(font
					(size 1.27 1.27)
					(thickness 0.15)
				)
				(justify left bottom)
				(hide yes)
			)
		)
		(property "License" "Apache-2.0"
			(at 278.13 54.61 0)
			(effects
				(font
					(size 1.27 1.27)
					(thickness 0.15)
				)
				(justify left bottom)
				(hide yes)
			)
		)
		(pin "1"
		)
		(instances
			(project "k410t-devboard"
				(path ""
					(reference "#PWR0335")
					(unit 1)
				)
			)
		)
	)
	(symbol
		(lib_id "antmicroCapacitors0402:C_10p_0402")
		(at 208.28 205.74 90)
		(unit 1)
		(exclude_from_sim no)
		(in_bom yes)
		(on_board yes)
		(dnp no)
		(fields_autoplaced yes)
		(property "Reference" "C273"
			(at 210.82 201.9235 90)
			(effects
				(font
					(size 1.27 1.27)
				)
				(justify right)
			)
		)
		(property "Value" "C_10p_0402"
			(at 218.44 185.42 0)
			(effects
				(font
					(size 1.27 1.27)
					(thickness 0.15)
				)
				(justify left bottom)
				(hide yes)
			)
		)
		(property "Footprint" "antmicro-footprints:C_0402_1005Metric"
			(at 220.98 185.42 0)
			(effects
				(font
					(size 1.27 1.27)
					(thickness 0.15)
				)
				(justify left bottom)
				(hide yes)
			)
		)
		(property "Datasheet" "https://www.murata.com/products/productdetail?partno=GCM1555C1H100GA16%23"
			(at 223.52 185.42 0)
			(effects
				(font
					(size 1.27 1.27)
					(thickness 0.15)
				)
				(justify left bottom)
				(hide yes)
			)
		)
		(property "Description" ""
			(at 208.28 205.74 0)
			(effects
				(font
					(size 1.27 1.27)
				)
			)
		)
		(property "Manufacturer" "Murata"
			(at 228.6 185.42 0)
			(effects
				(font
					(size 1.27 1.27)
					(thickness 0.15)
				)
				(justify left bottom)
				(hide yes)
			)
		)
		(property "MPN" "GCM1555C1H100GA16D"
			(at 226.06 185.42 0)
			(effects
				(font
					(size 1.27 1.27)
					(thickness 0.15)
				)
				(justify left bottom)
				(hide yes)
			)
		)
		(property "Val" "10p"
			(at 210.82 204.4635 90)
			(effects
				(font
					(size 1.27 1.27)
					(thickness 0.15)
				)
				(justify right)
			)
		)
		(property "License" "Apache-2.0"
			(at 231.14 185.42 0)
			(effects
				(font
					(size 1.27 1.27)
					(thickness 0.15)
				)
				(justify left bottom)
				(hide yes)
			)
		)
		(property "Author" "Antmicro"
			(at 233.68 185.42 0)
			(effects
				(font
					(size 1.27 1.27)
					(thickness 0.15)
				)
				(justify left bottom)
				(hide yes)
			)
		)
		(property "Voltage" "50V"
			(at 236.22 185.42 0)
			(effects
				(font
					(size 1.27 1.27)
				)
				(justify left bottom)
				(hide yes)
			)
		)
		(property "Dielectric" "C0G"
			(at 238.76 185.42 0)
			(effects
				(font
					(size 1.27 1.27)
				)
				(justify left bottom)
				(hide yes)
			)
		)
		(pin "1"
		)
		(pin "2"
		)
		(instances
			(project "k410t-devboard"
				(path ""
					(reference "C273")
					(unit 1)
				)
			)
		)
	)
	(symbol
		(lib_id "antmicroFerriteBeadsandChips:FB_120Z_2A_Murata-BLM18PG_0603")
		(at 300.99 157.48 0)
		(unit 1)
		(exclude_from_sim no)
		(in_bom yes)
		(on_board yes)
		(dnp no)
		(fields_autoplaced yes)
		(property "Reference" "FB9"
			(at 303.4919 151.13 0)
			(effects
				(font
					(size 1.27 1.27)
				)
			)
		)
		(property "Value" "FB_120Z_2A_Murata-BLM18PG_0603"
			(at 303.4919 153.67 0)
			(effects
				(font
					(size 1.27 1.27)
					(thickness 0.15)
				)
				(hide yes)
			)
		)
		(property "Footprint" "antmicro-footprints:FB_0603_1608Metric"
			(at 314.96 162.56 0)
			(effects
				(font
					(size 1.27 1.27)
					(thickness 0.15)
				)
				(justify left bottom)
				(hide yes)
			)
		)
		(property "Datasheet" "https://www.murata.com/en-us/products/productdata/8796738650142/ENFA0003.pdf"
			(at 314.96 165.1 0)
			(effects
				(font
					(size 1.27 1.27)
					(thickness 0.15)
				)
				(justify left bottom)
				(hide yes)
			)
		)
		(property "Description" ""
			(at 300.99 157.48 0)
			(effects
				(font
					(size 1.27 1.27)
				)
			)
		)
		(property "MPN" "BLM18PG121SN1D"
			(at 314.96 167.64 0)
			(effects
				(font
					(size 1.27 1.27)
					(thickness 0.15)
				)
				(justify left bottom)
				(hide yes)
			)
		)
		(property "Manufacturer" "Murata"
			(at 314.96 170.18 0)
			(effects
				(font
					(size 1.27 1.27)
					(thickness 0.15)
				)
				(justify left bottom)
				(hide yes)
			)
		)
		(property "Author" "Antmicro"
			(at 314.96 172.72 0)
			(effects
				(font
					(size 1.27 1.27)
					(thickness 0.15)
				)
				(justify left bottom)
				(hide yes)
			)
		)
		(property "License" "Apache-2.0"
			(at 314.96 175.26 0)
			(effects
				(font
					(size 1.27 1.27)
					(thickness 0.15)
				)
				(justify left bottom)
				(hide yes)
			)
		)
		(property "Val" "120Z/2A"
			(at 303.4919 153.67 0)
			(effects
				(font
					(size 1.27 1.27)
				)
			)
		)
		(property "Current" ""
			(at 321.31 180.34 0)
			(effects
				(font
					(size 1.27 1.27)
					(thickness 0.15)
				)
				(justify left bottom)
				(hide yes)
			)
		)
		(pin "1"
		)
		(pin "2"
		)
		(instances
			(project "k410t-devboard"
				(path ""
					(reference "FB9")
					(unit 1)
				)
			)
		)
	)
	(symbol
		(lib_id "antmicropower:GND")
		(at 177.8 222.25 0)
		(unit 1)
		(exclude_from_sim no)
		(in_bom yes)
		(on_board yes)
		(dnp no)
		(property "Reference" "#PWR0305"
			(at 177.8 228.6 0)
			(effects
				(font
					(size 1.27 1.27)
				)
				(hide yes)
			)
		)
		(property "Value" "GND"
			(at 177.8 226.06 0)
			(effects
				(font
					(size 1.27 1.27)
				)
			)
		)
		(property "Footprint" ""
			(at 186.69 229.87 0)
			(effects
				(font
					(size 1.27 1.27)
					(thickness 0.15)
				)
				(justify left bottom)
				(hide yes)
			)
		)
		(property "Datasheet" ""
			(at 186.69 234.95 0)
			(effects
				(font
					(size 1.27 1.27)
					(thickness 0.15)
				)
				(justify left bottom)
				(hide yes)
			)
		)
		(property "Description" ""
			(at 177.8 222.25 0)
			(effects
				(font
					(size 1.27 1.27)
				)
			)
		)
		(property "Author" "Antmicro"
			(at 186.69 229.87 0)
			(effects
				(font
					(size 1.27 1.27)
					(thickness 0.15)
				)
				(justify left bottom)
				(hide yes)
			)
		)
		(property "License" "Apache-2.0"
			(at 186.69 232.41 0)
			(effects
				(font
					(size 1.27 1.27)
					(thickness 0.15)
				)
				(justify left bottom)
				(hide yes)
			)
		)
		(pin "1"
		)
		(instances
			(project "k410t-devboard"
				(path ""
					(reference "#PWR0305")
					(unit 1)
				)
			)
		)
	)
	(symbol
		(lib_id "antmicroCapacitors0402:C_10p_0402")
		(at 233.68 205.74 90)
		(unit 1)
		(exclude_from_sim no)
		(in_bom yes)
		(on_board yes)
		(dnp no)
		(fields_autoplaced yes)
		(property "Reference" "C276"
			(at 236.22 201.9235 90)
			(effects
				(font
					(size 1.27 1.27)
				)
				(justify right)
			)
		)
		(property "Value" "C_10p_0402"
			(at 243.84 185.42 0)
			(effects
				(font
					(size 1.27 1.27)
					(thickness 0.15)
				)
				(justify left bottom)
				(hide yes)
			)
		)
		(property "Footprint" "antmicro-footprints:C_0402_1005Metric"
			(at 246.38 185.42 0)
			(effects
				(font
					(size 1.27 1.27)
					(thickness 0.15)
				)
				(justify left bottom)
				(hide yes)
			)
		)
		(property "Datasheet" "https://www.murata.com/products/productdetail?partno=GCM1555C1H100GA16%23"
			(at 248.92 185.42 0)
			(effects
				(font
					(size 1.27 1.27)
					(thickness 0.15)
				)
				(justify left bottom)
				(hide yes)
			)
		)
		(property "Description" ""
			(at 233.68 205.74 0)
			(effects
				(font
					(size 1.27 1.27)
				)
			)
		)
		(property "Manufacturer" "Murata"
			(at 254 185.42 0)
			(effects
				(font
					(size 1.27 1.27)
					(thickness 0.15)
				)
				(justify left bottom)
				(hide yes)
			)
		)
		(property "MPN" "GCM1555C1H100GA16D"
			(at 251.46 185.42 0)
			(effects
				(font
					(size 1.27 1.27)
					(thickness 0.15)
				)
				(justify left bottom)
				(hide yes)
			)
		)
		(property "Val" "10p"
			(at 236.22 204.4635 90)
			(effects
				(font
					(size 1.27 1.27)
					(thickness 0.15)
				)
				(justify right)
			)
		)
		(property "License" "Apache-2.0"
			(at 256.54 185.42 0)
			(effects
				(font
					(size 1.27 1.27)
					(thickness 0.15)
				)
				(justify left bottom)
				(hide yes)
			)
		)
		(property "Author" "Antmicro"
			(at 259.08 185.42 0)
			(effects
				(font
					(size 1.27 1.27)
					(thickness 0.15)
				)
				(justify left bottom)
				(hide yes)
			)
		)
		(property "Voltage" "50V"
			(at 261.62 185.42 0)
			(effects
				(font
					(size 1.27 1.27)
				)
				(justify left bottom)
				(hide yes)
			)
		)
		(property "Dielectric" "C0G"
			(at 264.16 185.42 0)
			(effects
				(font
					(size 1.27 1.27)
				)
				(justify left bottom)
				(hide yes)
			)
		)
		(pin "1"
		)
		(pin "2"
		)
		(instances
			(project "k410t-devboard"
				(path ""
					(reference "C276")
					(unit 1)
				)
			)
		)
	)
	(symbol
		(lib_id "antmicroCapacitors0402:C_10u_0402")
		(at 220.98 162.56 90)
		(unit 1)
		(exclude_from_sim no)
		(in_bom yes)
		(on_board yes)
		(dnp no)
		(property "Reference" "C274"
			(at 221.615 158.115 90)
			(effects
				(font
					(size 1.27 1.27)
				)
				(justify right)
			)
		)
		(property "Value" "C_10u_0402"
			(at 231.14 142.24 0)
			(effects
				(font
					(size 1.27 1.27)
					(thickness 0.15)
				)
				(justify left bottom)
				(hide yes)
			)
		)
		(property "Footprint" "antmicro-footprints:C_0402_1005Metric"
			(at 233.68 142.24 0)
			(effects
				(font
					(size 1.27 1.27)
					(thickness 0.15)
				)
				(justify left bottom)
				(hide yes)
			)
		)
		(property "Datasheet" "https://www.yageo.com/en/Chart/Download/pdf/CC0402MRX5R5BB106"
			(at 236.22 142.24 0)
			(effects
				(font
					(size 1.27 1.27)
					(thickness 0.15)
				)
				(justify left bottom)
				(hide yes)
			)
		)
		(property "Description" ""
			(at 220.98 162.56 0)
			(effects
				(font
					(size 1.27 1.27)
				)
			)
		)
		(property "Manufacturer" "YAGEO"
			(at 241.3 142.24 0)
			(effects
				(font
					(size 1.27 1.27)
					(thickness 0.15)
				)
				(justify left bottom)
				(hide yes)
			)
		)
		(property "MPN" "CC0402MRX5R5BB106"
			(at 238.76 142.24 0)
			(effects
				(font
					(size 1.27 1.27)
					(thickness 0.15)
				)
				(justify left bottom)
				(hide yes)
			)
		)
		(property "Val" "10u"
			(at 221.615 161.925 90)
			(effects
				(font
					(size 1.27 1.27)
					(thickness 0.15)
				)
				(justify right)
			)
		)
		(property "License" "Apache-2.0"
			(at 243.84 142.24 0)
			(effects
				(font
					(size 1.27 1.27)
					(thickness 0.15)
				)
				(justify left bottom)
				(hide yes)
			)
		)
		(property "Author" "Antmicro"
			(at 246.38 142.24 0)
			(effects
				(font
					(size 1.27 1.27)
					(thickness 0.15)
				)
				(justify left bottom)
				(hide yes)
			)
		)
		(property "Voltage" ""
			(at 248.92 142.24 0)
			(effects
				(font
					(size 1.27 1.27)
				)
				(justify left bottom)
				(hide yes)
			)
		)
		(property "Dielectric" ""
			(at 251.46 142.24 0)
			(effects
				(font
					(size 1.27 1.27)
				)
				(justify left bottom)
				(hide yes)
			)
		)
		(pin "1"
		)
		(pin "2"
		)
		(instances
			(project "k410t-devboard"
				(path ""
					(reference "C274")
					(unit 1)
				)
			)
		)
	)
	(symbol
		(lib_id "antmicroCapacitors0402:C_100n_0402")
		(at 127 162.56 90)
		(unit 1)
		(exclude_from_sim no)
		(in_bom yes)
		(on_board yes)
		(dnp no)
		(property "Reference" "C257"
			(at 127.635 158.115 90)
			(effects
				(font
					(size 1.27 1.27)
				)
				(justify right)
			)
		)
		(property "Value" "C_100n_0402"
			(at 137.16 142.24 0)
			(effects
				(font
					(size 1.27 1.27)
					(thickness 0.15)
				)
				(justify left bottom)
				(hide yes)
			)
		)
		(property "Footprint" "antmicro-footprints:C_0402_1005Metric"
			(at 139.7 142.24 0)
			(effects
				(font
					(size 1.27 1.27)
					(thickness 0.15)
				)
				(justify left bottom)
				(hide yes)
			)
		)
		(property "Datasheet" "https://www.murata.com/products/productdetail?partno=GRM155R61H104KE14%23"
			(at 142.24 142.24 0)
			(effects
				(font
					(size 1.27 1.27)
					(thickness 0.15)
				)
				(justify left bottom)
				(hide yes)
			)
		)
		(property "Description" ""
			(at 127 162.56 0)
			(effects
				(font
					(size 1.27 1.27)
				)
			)
		)
		(property "Manufacturer" "Murata"
			(at 147.32 142.24 0)
			(effects
				(font
					(size 1.27 1.27)
					(thickness 0.15)
				)
				(justify left bottom)
				(hide yes)
			)
		)
		(property "MPN" "GRM155R61H104KE14D"
			(at 144.78 142.24 0)
			(effects
				(font
					(size 1.27 1.27)
					(thickness 0.15)
				)
				(justify left bottom)
				(hide yes)
			)
		)
		(property "Val" "100n"
			(at 127.635 161.925 90)
			(effects
				(font
					(size 1.27 1.27)
					(thickness 0.15)
				)
				(justify right)
			)
		)
		(property "License" "Apache-2.0"
			(at 149.86 142.24 0)
			(effects
				(font
					(size 1.27 1.27)
					(thickness 0.15)
				)
				(justify left bottom)
				(hide yes)
			)
		)
		(property "Author" "Antmicro"
			(at 152.4 142.24 0)
			(effects
				(font
					(size 1.27 1.27)
					(thickness 0.15)
				)
				(justify left bottom)
				(hide yes)
			)
		)
		(property "Voltage" "50V"
			(at 154.94 142.24 0)
			(effects
				(font
					(size 1.27 1.27)
				)
				(justify left bottom)
				(hide yes)
			)
		)
		(property "Dielectric" "X5R"
			(at 157.48 142.24 0)
			(effects
				(font
					(size 1.27 1.27)
				)
				(justify left bottom)
				(hide yes)
			)
		)
		(pin "1"
		)
		(pin "2"
		)
		(instances
			(project "k410t-devboard"
				(path ""
					(reference "C257")
					(unit 1)
				)
			)
		)
	)
	(symbol
		(lib_id "antmicropower:+3.3V")
		(at 396.24 105.41 0)
		(unit 1)
		(exclude_from_sim no)
		(in_bom yes)
		(on_board yes)
		(dnp no)
		(property "Reference" "#PWR0317"
			(at 396.24 109.22 0)
			(effects
				(font
					(size 1.27 1.27)
				)
				(hide yes)
			)
		)
		(property "Value" "+3V3"
			(at 396.24 101.854 0)
			(effects
				(font
					(size 1.27 1.27)
				)
			)
		)
		(property "Footprint" ""
			(at 396.24 105.41 0)
			(effects
				(font
					(size 1.27 1.27)
				)
				(hide yes)
			)
		)
		(property "Datasheet" ""
			(at 396.24 105.41 0)
			(effects
				(font
					(size 1.27 1.27)
				)
				(hide yes)
			)
		)
		(property "Description" ""
			(at 396.24 105.41 0)
			(effects
				(font
					(size 1.27 1.27)
				)
			)
		)
		(pin "1"
		)
		(instances
			(project "k410t-devboard"
				(path ""
					(reference "#PWR0317")
					(unit 1)
				)
			)
		)
	)
	(symbol
		(lib_id "antmicroCapacitors0402:C_100n_0402")
		(at 269.24 43.18 90)
		(unit 1)
		(exclude_from_sim no)
		(in_bom yes)
		(on_board yes)
		(dnp no)
		(property "Reference" "C287"
			(at 269.875 38.735 90)
			(effects
				(font
					(size 1.27 1.27)
				)
				(justify right)
			)
		)
		(property "Value" "C_100n_0402"
			(at 279.4 22.86 0)
			(effects
				(font
					(size 1.27 1.27)
					(thickness 0.15)
				)
				(justify left bottom)
				(hide yes)
			)
		)
		(property "Footprint" "antmicro-footprints:C_0402_1005Metric"
			(at 281.94 22.86 0)
			(effects
				(font
					(size 1.27 1.27)
					(thickness 0.15)
				)
				(justify left bottom)
				(hide yes)
			)
		)
		(property "Datasheet" "https://www.murata.com/products/productdetail?partno=GRM155R61H104KE14%23"
			(at 284.48 22.86 0)
			(effects
				(font
					(size 1.27 1.27)
					(thickness 0.15)
				)
				(justify left bottom)
				(hide yes)
			)
		)
		(property "Description" ""
			(at 269.24 43.18 0)
			(effects
				(font
					(size 1.27 1.27)
				)
			)
		)
		(property "Manufacturer" "Murata"
			(at 289.56 22.86 0)
			(effects
				(font
					(size 1.27 1.27)
					(thickness 0.15)
				)
				(justify left bottom)
				(hide yes)
			)
		)
		(property "MPN" "GRM155R61H104KE14D"
			(at 287.02 22.86 0)
			(effects
				(font
					(size 1.27 1.27)
					(thickness 0.15)
				)
				(justify left bottom)
				(hide yes)
			)
		)
		(property "Val" "100n"
			(at 269.875 42.545 90)
			(effects
				(font
					(size 1.27 1.27)
					(thickness 0.15)
				)
				(justify right)
			)
		)
		(property "License" "Apache-2.0"
			(at 292.1 22.86 0)
			(effects
				(font
					(size 1.27 1.27)
					(thickness 0.15)
				)
				(justify left bottom)
				(hide yes)
			)
		)
		(property "Author" "Antmicro"
			(at 294.64 22.86 0)
			(effects
				(font
					(size 1.27 1.27)
					(thickness 0.15)
				)
				(justify left bottom)
				(hide yes)
			)
		)
		(property "Voltage" "50V"
			(at 297.18 22.86 0)
			(effects
				(font
					(size 1.27 1.27)
				)
				(justify left bottom)
				(hide yes)
			)
		)
		(property "Dielectric" "X5R"
			(at 299.72 22.86 0)
			(effects
				(font
					(size 1.27 1.27)
				)
				(justify left bottom)
				(hide yes)
			)
		)
		(pin "1"
		)
		(pin "2"
		)
		(instances
			(project "k410t-devboard"
				(path ""
					(reference "C287")
					(unit 1)
				)
			)
		)
	)
	(symbol
		(lib_id "antmicroCapacitors0402:C_100n_0402")
		(at 247.65 43.18 90)
		(unit 1)
		(exclude_from_sim no)
		(in_bom yes)
		(on_board yes)
		(dnp no)
		(property "Reference" "C282"
			(at 248.285 38.735 90)
			(effects
				(font
					(size 1.27 1.27)
				)
				(justify right)
			)
		)
		(property "Value" "C_100n_0402"
			(at 257.81 22.86 0)
			(effects
				(font
					(size 1.27 1.27)
					(thickness 0.15)
				)
				(justify left bottom)
				(hide yes)
			)
		)
		(property "Footprint" "antmicro-footprints:C_0402_1005Metric"
			(at 260.35 22.86 0)
			(effects
				(font
					(size 1.27 1.27)
					(thickness 0.15)
				)
				(justify left bottom)
				(hide yes)
			)
		)
		(property "Datasheet" "https://www.murata.com/products/productdetail?partno=GRM155R61H104KE14%23"
			(at 262.89 22.86 0)
			(effects
				(font
					(size 1.27 1.27)
					(thickness 0.15)
				)
				(justify left bottom)
				(hide yes)
			)
		)
		(property "Description" ""
			(at 247.65 43.18 0)
			(effects
				(font
					(size 1.27 1.27)
				)
			)
		)
		(property "Manufacturer" "Murata"
			(at 267.97 22.86 0)
			(effects
				(font
					(size 1.27 1.27)
					(thickness 0.15)
				)
				(justify left bottom)
				(hide yes)
			)
		)
		(property "MPN" "GRM155R61H104KE14D"
			(at 265.43 22.86 0)
			(effects
				(font
					(size 1.27 1.27)
					(thickness 0.15)
				)
				(justify left bottom)
				(hide yes)
			)
		)
		(property "Val" "100n"
			(at 248.285 42.545 90)
			(effects
				(font
					(size 1.27 1.27)
					(thickness 0.15)
				)
				(justify right)
			)
		)
		(property "License" "Apache-2.0"
			(at 270.51 22.86 0)
			(effects
				(font
					(size 1.27 1.27)
					(thickness 0.15)
				)
				(justify left bottom)
				(hide yes)
			)
		)
		(property "Author" "Antmicro"
			(at 273.05 22.86 0)
			(effects
				(font
					(size 1.27 1.27)
					(thickness 0.15)
				)
				(justify left bottom)
				(hide yes)
			)
		)
		(property "Voltage" "50V"
			(at 275.59 22.86 0)
			(effects
				(font
					(size 1.27 1.27)
				)
				(justify left bottom)
				(hide yes)
			)
		)
		(property "Dielectric" "X5R"
			(at 278.13 22.86 0)
			(effects
				(font
					(size 1.27 1.27)
				)
				(justify left bottom)
				(hide yes)
			)
		)
		(pin "1"
		)
		(pin "2"
		)
		(instances
			(project "k410t-devboard"
				(path ""
					(reference "C282")
					(unit 1)
				)
			)
		)
	)
	(symbol
		(lib_id "antmicropower:GND")
		(at 144.78 132.08 0)
		(unit 1)
		(exclude_from_sim no)
		(in_bom yes)
		(on_board yes)
		(dnp no)
		(fields_autoplaced yes)
		(property "Reference" "#PWR0302"
			(at 144.78 138.43 0)
			(effects
				(font
					(size 1.27 1.27)
				)
				(hide yes)
			)
		)
		(property "Value" "GND"
			(at 144.78 135.89 0)
			(effects
				(font
					(size 1.27 1.27)
				)
			)
		)
		(property "Footprint" ""
			(at 153.67 139.7 0)
			(effects
				(font
					(size 1.27 1.27)
					(thickness 0.15)
				)
				(justify left bottom)
				(hide yes)
			)
		)
		(property "Datasheet" ""
			(at 153.67 144.78 0)
			(effects
				(font
					(size 1.27 1.27)
					(thickness 0.15)
				)
				(justify left bottom)
				(hide yes)
			)
		)
		(property "Description" ""
			(at 144.78 132.08 0)
			(effects
				(font
					(size 1.27 1.27)
				)
			)
		)
		(property "Author" "Antmicro"
			(at 153.67 139.7 0)
			(effects
				(font
					(size 1.27 1.27)
					(thickness 0.15)
				)
				(justify left bottom)
				(hide yes)
			)
		)
		(property "License" "Apache-2.0"
			(at 153.67 142.24 0)
			(effects
				(font
					(size 1.27 1.27)
					(thickness 0.15)
				)
				(justify left bottom)
				(hide yes)
			)
		)
		(pin "1"
		)
		(instances
			(project "k410t-devboard"
				(path ""
					(reference "#PWR0302")
					(unit 1)
				)
			)
		)
	)
	(symbol
		(lib_id "antmicroCapacitors0402:C_100n_0402")
		(at 152.4 43.18 90)
		(unit 1)
		(exclude_from_sim no)
		(in_bom yes)
		(on_board yes)
		(dnp no)
		(fields_autoplaced yes)
		(property "Reference" "C265"
			(at 154.94 39.3635 90)
			(effects
				(font
					(size 1.27 1.27)
				)
				(justify right)
			)
		)
		(property "Value" "C_100n_0402"
			(at 162.56 22.86 0)
			(effects
				(font
					(size 1.27 1.27)
					(thickness 0.15)
				)
				(justify left bottom)
				(hide yes)
			)
		)
		(property "Footprint" "antmicro-footprints:C_0402_1005Metric"
			(at 165.1 22.86 0)
			(effects
				(font
					(size 1.27 1.27)
					(thickness 0.15)
				)
				(justify left bottom)
				(hide yes)
			)
		)
		(property "Datasheet" "https://www.murata.com/products/productdetail?partno=GRM155R61H104KE14%23"
			(at 167.64 22.86 0)
			(effects
				(font
					(size 1.27 1.27)
					(thickness 0.15)
				)
				(justify left bottom)
				(hide yes)
			)
		)
		(property "Description" ""
			(at 152.4 43.18 0)
			(effects
				(font
					(size 1.27 1.27)
				)
			)
		)
		(property "Manufacturer" "Murata"
			(at 172.72 22.86 0)
			(effects
				(font
					(size 1.27 1.27)
					(thickness 0.15)
				)
				(justify left bottom)
				(hide yes)
			)
		)
		(property "MPN" "GRM155R61H104KE14D"
			(at 170.18 22.86 0)
			(effects
				(font
					(size 1.27 1.27)
					(thickness 0.15)
				)
				(justify left bottom)
				(hide yes)
			)
		)
		(property "Val" "100n"
			(at 154.94 41.9035 90)
			(effects
				(font
					(size 1.27 1.27)
					(thickness 0.15)
				)
				(justify right)
			)
		)
		(property "License" "Apache-2.0"
			(at 175.26 22.86 0)
			(effects
				(font
					(size 1.27 1.27)
					(thickness 0.15)
				)
				(justify left bottom)
				(hide yes)
			)
		)
		(property "Author" "Antmicro"
			(at 177.8 22.86 0)
			(effects
				(font
					(size 1.27 1.27)
					(thickness 0.15)
				)
				(justify left bottom)
				(hide yes)
			)
		)
		(property "Voltage" "50V"
			(at 180.34 22.86 0)
			(effects
				(font
					(size 1.27 1.27)
				)
				(justify left bottom)
				(hide yes)
			)
		)
		(property "Dielectric" "X5R"
			(at 182.88 22.86 0)
			(effects
				(font
					(size 1.27 1.27)
				)
				(justify left bottom)
				(hide yes)
			)
		)
		(pin "1"
		)
		(pin "2"
		)
		(instances
			(project "k410t-devboard"
				(path ""
					(reference "C265")
					(unit 1)
				)
			)
		)
	)
	(symbol
		(lib_id "antmicropower:GND")
		(at 237.49 29.21 0)
		(mirror y)
		(unit 1)
		(exclude_from_sim no)
		(in_bom yes)
		(on_board yes)
		(dnp no)
		(fields_autoplaced yes)
		(property "Reference" "#PWR0320"
			(at 237.49 35.56 0)
			(effects
				(font
					(size 1.27 1.27)
				)
				(hide yes)
			)
		)
		(property "Value" "GND"
			(at 237.49 33.02 0)
			(effects
				(font
					(size 1.27 1.27)
				)
			)
		)
		(property "Footprint" ""
			(at 228.6 36.83 0)
			(effects
				(font
					(size 1.27 1.27)
					(thickness 0.15)
				)
				(justify left bottom)
				(hide yes)
			)
		)
		(property "Datasheet" ""
			(at 228.6 41.91 0)
			(effects
				(font
					(size 1.27 1.27)
					(thickness 0.15)
				)
				(justify left bottom)
				(hide yes)
			)
		)
		(property "Description" ""
			(at 237.49 29.21 0)
			(effects
				(font
					(size 1.27 1.27)
				)
			)
		)
		(property "Author" "Antmicro"
			(at 228.6 36.83 0)
			(effects
				(font
					(size 1.27 1.27)
					(thickness 0.15)
				)
				(justify left bottom)
				(hide yes)
			)
		)
		(property "License" "Apache-2.0"
			(at 228.6 39.37 0)
			(effects
				(font
					(size 1.27 1.27)
					(thickness 0.15)
				)
				(justify left bottom)
				(hide yes)
			)
		)
		(pin "1"
		)
		(instances
			(project "k410t-devboard"
				(path ""
					(reference "#PWR0320")
					(unit 1)
				)
			)
		)
	)
	(symbol
		(lib_id "antmicropower:GND")
		(at 259.08 44.45 0)
		(unit 1)
		(exclude_from_sim no)
		(in_bom yes)
		(on_board yes)
		(dnp no)
		(fields_autoplaced yes)
		(property "Reference" "#PWR0328"
			(at 259.08 50.8 0)
			(effects
				(font
					(size 1.27 1.27)
				)
				(hide yes)
			)
		)
		(property "Value" "GND"
			(at 259.08 48.26 0)
			(effects
				(font
					(size 1.27 1.27)
				)
			)
		)
		(property "Footprint" ""
			(at 267.97 52.07 0)
			(effects
				(font
					(size 1.27 1.27)
					(thickness 0.15)
				)
				(justify left bottom)
				(hide yes)
			)
		)
		(property "Datasheet" ""
			(at 267.97 57.15 0)
			(effects
				(font
					(size 1.27 1.27)
					(thickness 0.15)
				)
				(justify left bottom)
				(hide yes)
			)
		)
		(property "Description" ""
			(at 259.08 44.45 0)
			(effects
				(font
					(size 1.27 1.27)
				)
			)
		)
		(property "Author" "Antmicro"
			(at 267.97 52.07 0)
			(effects
				(font
					(size 1.27 1.27)
					(thickness 0.15)
				)
				(justify left bottom)
				(hide yes)
			)
		)
		(property "License" "Apache-2.0"
			(at 267.97 54.61 0)
			(effects
				(font
					(size 1.27 1.27)
					(thickness 0.15)
				)
				(justify left bottom)
				(hide yes)
			)
		)
		(pin "1"
		)
		(instances
			(project "k410t-devboard"
				(path ""
					(reference "#PWR0328")
					(unit 1)
				)
			)
		)
	)
	(symbol
		(lib_id "antmicroResistors0402:R_49R9_0402")
		(at 220.98 186.69 90)
		(unit 1)
		(exclude_from_sim no)
		(in_bom yes)
		(on_board yes)
		(dnp no)
		(fields_autoplaced yes)
		(property "Reference" "R247"
			(at 223.52 182.8799 90)
			(effects
				(font
					(size 1.27 1.27)
				)
				(justify right)
			)
		)
		(property "Value" "R_49R9_0402"
			(at 233.68 166.37 0)
			(effects
				(font
					(size 1.27 1.27)
					(thickness 0.15)
				)
				(justify left bottom)
				(hide yes)
			)
		)
		(property "Footprint" "antmicro-footprints:R_0402_1005Metric"
			(at 236.22 166.37 0)
			(effects
				(font
					(size 1.27 1.27)
					(thickness 0.15)
				)
				(justify left bottom)
				(hide yes)
			)
		)
		(property "Datasheet" "https://www.bourns.com/docs/product-datasheets/cr.pdf"
			(at 238.76 166.37 0)
			(effects
				(font
					(size 1.27 1.27)
					(thickness 0.15)
				)
				(justify left bottom)
				(hide yes)
			)
		)
		(property "Description" ""
			(at 220.98 186.69 0)
			(effects
				(font
					(size 1.27 1.27)
				)
			)
		)
		(property "Manufacturer" "Bourns"
			(at 243.84 166.37 0)
			(effects
				(font
					(size 1.27 1.27)
					(thickness 0.15)
				)
				(justify left bottom)
				(hide yes)
			)
		)
		(property "MPN" "CR0402-FX-49R9GLF"
			(at 241.3 166.37 0)
			(effects
				(font
					(size 1.27 1.27)
					(thickness 0.15)
				)
				(justify left bottom)
				(hide yes)
			)
		)
		(property "Val" "49R9"
			(at 223.52 185.4199 90)
			(effects
				(font
					(size 1.27 1.27)
					(thickness 0.15)
				)
				(justify right)
			)
		)
		(property "License" "Apache-2.0"
			(at 246.38 166.37 0)
			(effects
				(font
					(size 1.27 1.27)
					(thickness 0.15)
				)
				(justify left bottom)
				(hide yes)
			)
		)
		(property "Author" "Antmicro"
			(at 248.92 166.37 0)
			(effects
				(font
					(size 1.27 1.27)
					(thickness 0.15)
				)
				(justify left bottom)
				(hide yes)
			)
		)
		(property "Tolerance" "1%"
			(at 231.14 166.37 0)
			(effects
				(font
					(size 1.27 1.27)
				)
				(justify left bottom)
				(hide yes)
			)
		)
		(pin "1"
		)
		(pin "2"
		)
		(instances
			(project "k410t-devboard"
				(path ""
					(reference "R247")
					(unit 1)
				)
			)
		)
	)
	(symbol
		(lib_id "antmicropower:GND")
		(at 119.38 241.3 0)
		(unit 1)
		(exclude_from_sim no)
		(in_bom yes)
		(on_board yes)
		(dnp no)
		(property "Reference" "#PWR0288"
			(at 119.38 247.65 0)
			(effects
				(font
					(size 1.27 1.27)
				)
				(hide yes)
			)
		)
		(property "Value" "GND"
			(at 119.38 245.11 0)
			(effects
				(font
					(size 1.27 1.27)
				)
			)
		)
		(property "Footprint" ""
			(at 128.27 248.92 0)
			(effects
				(font
					(size 1.27 1.27)
					(thickness 0.15)
				)
				(justify left bottom)
				(hide yes)
			)
		)
		(property "Datasheet" ""
			(at 128.27 254 0)
			(effects
				(font
					(size 1.27 1.27)
					(thickness 0.15)
				)
				(justify left bottom)
				(hide yes)
			)
		)
		(property "Description" ""
			(at 119.38 241.3 0)
			(effects
				(font
					(size 1.27 1.27)
				)
			)
		)
		(property "Author" "Antmicro"
			(at 128.27 248.92 0)
			(effects
				(font
					(size 1.27 1.27)
					(thickness 0.15)
				)
				(justify left bottom)
				(hide yes)
			)
		)
		(property "License" "Apache-2.0"
			(at 128.27 251.46 0)
			(effects
				(font
					(size 1.27 1.27)
					(thickness 0.15)
				)
				(justify left bottom)
				(hide yes)
			)
		)
		(pin "1"
		)
		(instances
			(project "k410t-devboard"
				(path ""
					(reference "#PWR0288")
					(unit 1)
				)
			)
		)
	)
	(symbol
		(lib_id "antmicroCapacitors0402:C_10u_0402")
		(at 247.65 162.56 90)
		(unit 1)
		(exclude_from_sim no)
		(in_bom yes)
		(on_board yes)
		(dnp no)
		(property "Reference" "C280"
			(at 248.285 158.115 90)
			(effects
				(font
					(size 1.27 1.27)
				)
				(justify right)
			)
		)
		(property "Value" "C_10u_0402"
			(at 257.81 142.24 0)
			(effects
				(font
					(size 1.27 1.27)
					(thickness 0.15)
				)
				(justify left bottom)
				(hide yes)
			)
		)
		(property "Footprint" "antmicro-footprints:C_0402_1005Metric"
			(at 260.35 142.24 0)
			(effects
				(font
					(size 1.27 1.27)
					(thickness 0.15)
				)
				(justify left bottom)
				(hide yes)
			)
		)
		(property "Datasheet" "https://www.yageo.com/en/Chart/Download/pdf/CC0402MRX5R5BB106"
			(at 262.89 142.24 0)
			(effects
				(font
					(size 1.27 1.27)
					(thickness 0.15)
				)
				(justify left bottom)
				(hide yes)
			)
		)
		(property "Description" ""
			(at 247.65 162.56 0)
			(effects
				(font
					(size 1.27 1.27)
				)
			)
		)
		(property "Manufacturer" "YAGEO"
			(at 267.97 142.24 0)
			(effects
				(font
					(size 1.27 1.27)
					(thickness 0.15)
				)
				(justify left bottom)
				(hide yes)
			)
		)
		(property "MPN" "CC0402MRX5R5BB106"
			(at 265.43 142.24 0)
			(effects
				(font
					(size 1.27 1.27)
					(thickness 0.15)
				)
				(justify left bottom)
				(hide yes)
			)
		)
		(property "Val" "10u"
			(at 248.285 161.925 90)
			(effects
				(font
					(size 1.27 1.27)
					(thickness 0.15)
				)
				(justify right)
			)
		)
		(property "License" "Apache-2.0"
			(at 270.51 142.24 0)
			(effects
				(font
					(size 1.27 1.27)
					(thickness 0.15)
				)
				(justify left bottom)
				(hide yes)
			)
		)
		(property "Author" "Antmicro"
			(at 273.05 142.24 0)
			(effects
				(font
					(size 1.27 1.27)
					(thickness 0.15)
				)
				(justify left bottom)
				(hide yes)
			)
		)
		(property "Voltage" ""
			(at 275.59 142.24 0)
			(effects
				(font
					(size 1.27 1.27)
				)
				(justify left bottom)
				(hide yes)
			)
		)
		(property "Dielectric" ""
			(at 278.13 142.24 0)
			(effects
				(font
					(size 1.27 1.27)
				)
				(justify left bottom)
				(hide yes)
			)
		)
		(pin "1"
		)
		(pin "2"
		)
		(instances
			(project "k410t-devboard"
				(path ""
					(reference "C280")
					(unit 1)
				)
			)
		)
	)
	(symbol
		(lib_id "antmicroResistors0402:R_49R9_0402")
		(at 246.38 186.69 90)
		(unit 1)
		(exclude_from_sim no)
		(in_bom yes)
		(on_board yes)
		(dnp no)
		(fields_autoplaced yes)
		(property "Reference" "R250"
			(at 248.92 182.8799 90)
			(effects
				(font
					(size 1.27 1.27)
				)
				(justify right)
			)
		)
		(property "Value" "R_49R9_0402"
			(at 259.08 166.37 0)
			(effects
				(font
					(size 1.27 1.27)
					(thickness 0.15)
				)
				(justify left bottom)
				(hide yes)
			)
		)
		(property "Footprint" "antmicro-footprints:R_0402_1005Metric"
			(at 261.62 166.37 0)
			(effects
				(font
					(size 1.27 1.27)
					(thickness 0.15)
				)
				(justify left bottom)
				(hide yes)
			)
		)
		(property "Datasheet" "https://www.bourns.com/docs/product-datasheets/cr.pdf"
			(at 264.16 166.37 0)
			(effects
				(font
					(size 1.27 1.27)
					(thickness 0.15)
				)
				(justify left bottom)
				(hide yes)
			)
		)
		(property "Description" ""
			(at 246.38 186.69 0)
			(effects
				(font
					(size 1.27 1.27)
				)
			)
		)
		(property "Manufacturer" "Bourns"
			(at 269.24 166.37 0)
			(effects
				(font
					(size 1.27 1.27)
					(thickness 0.15)
				)
				(justify left bottom)
				(hide yes)
			)
		)
		(property "MPN" "CR0402-FX-49R9GLF"
			(at 266.7 166.37 0)
			(effects
				(font
					(size 1.27 1.27)
					(thickness 0.15)
				)
				(justify left bottom)
				(hide yes)
			)
		)
		(property "Val" "49R9"
			(at 248.92 185.4199 90)
			(effects
				(font
					(size 1.27 1.27)
					(thickness 0.15)
				)
				(justify right)
			)
		)
		(property "License" "Apache-2.0"
			(at 271.78 166.37 0)
			(effects
				(font
					(size 1.27 1.27)
					(thickness 0.15)
				)
				(justify left bottom)
				(hide yes)
			)
		)
		(property "Author" "Antmicro"
			(at 274.32 166.37 0)
			(effects
				(font
					(size 1.27 1.27)
					(thickness 0.15)
				)
				(justify left bottom)
				(hide yes)
			)
		)
		(property "Tolerance" "1%"
			(at 256.54 166.37 0)
			(effects
				(font
					(size 1.27 1.27)
				)
				(justify left bottom)
				(hide yes)
			)
		)
		(pin "1"
		)
		(pin "2"
		)
		(instances
			(project "k410t-devboard"
				(path ""
					(reference "R250")
					(unit 1)
				)
			)
		)
	)
	(symbol
		(lib_id "antmicropower:GND")
		(at 317.5 29.21 0)
		(unit 1)
		(exclude_from_sim no)
		(in_bom yes)
		(on_board yes)
		(dnp no)
		(fields_autoplaced yes)
		(property "Reference" "#PWR0340"
			(at 317.5 35.56 0)
			(effects
				(font
					(size 1.27 1.27)
				)
				(hide yes)
			)
		)
		(property "Value" "GND"
			(at 317.5 33.02 0)
			(effects
				(font
					(size 1.27 1.27)
				)
			)
		)
		(property "Footprint" ""
			(at 326.39 36.83 0)
			(effects
				(font
					(size 1.27 1.27)
					(thickness 0.15)
				)
				(justify left bottom)
				(hide yes)
			)
		)
		(property "Datasheet" ""
			(at 326.39 41.91 0)
			(effects
				(font
					(size 1.27 1.27)
					(thickness 0.15)
				)
				(justify left bottom)
				(hide yes)
			)
		)
		(property "Description" ""
			(at 317.5 29.21 0)
			(effects
				(font
					(size 1.27 1.27)
				)
			)
		)
		(property "Author" "Antmicro"
			(at 326.39 36.83 0)
			(effects
				(font
					(size 1.27 1.27)
					(thickness 0.15)
				)
				(justify left bottom)
				(hide yes)
			)
		)
		(property "License" "Apache-2.0"
			(at 326.39 39.37 0)
			(effects
				(font
					(size 1.27 1.27)
					(thickness 0.15)
				)
				(justify left bottom)
				(hide yes)
			)
		)
		(pin "1"
		)
		(instances
			(project "k410t-devboard"
				(path ""
					(reference "#PWR0340")
					(unit 1)
				)
			)
		)
	)
	(symbol
		(lib_id "antmicroCapacitors0402:C_100n_0402")
		(at 152.4 26.67 90)
		(unit 1)
		(exclude_from_sim no)
		(in_bom yes)
		(on_board yes)
		(dnp no)
		(fields_autoplaced yes)
		(property "Reference" "C264"
			(at 154.94 22.8535 90)
			(effects
				(font
					(size 1.27 1.27)
				)
				(justify right)
			)
		)
		(property "Value" "C_100n_0402"
			(at 162.56 6.35 0)
			(effects
				(font
					(size 1.27 1.27)
					(thickness 0.15)
				)
				(justify left bottom)
				(hide yes)
			)
		)
		(property "Footprint" "antmicro-footprints:C_0402_1005Metric"
			(at 165.1 6.35 0)
			(effects
				(font
					(size 1.27 1.27)
					(thickness 0.15)
				)
				(justify left bottom)
				(hide yes)
			)
		)
		(property "Datasheet" "https://www.murata.com/products/productdetail?partno=GRM155R61H104KE14%23"
			(at 167.64 6.35 0)
			(effects
				(font
					(size 1.27 1.27)
					(thickness 0.15)
				)
				(justify left bottom)
				(hide yes)
			)
		)
		(property "Description" ""
			(at 152.4 26.67 0)
			(effects
				(font
					(size 1.27 1.27)
				)
			)
		)
		(property "Manufacturer" "Murata"
			(at 172.72 6.35 0)
			(effects
				(font
					(size 1.27 1.27)
					(thickness 0.15)
				)
				(justify left bottom)
				(hide yes)
			)
		)
		(property "MPN" "GRM155R61H104KE14D"
			(at 170.18 6.35 0)
			(effects
				(font
					(size 1.27 1.27)
					(thickness 0.15)
				)
				(justify left bottom)
				(hide yes)
			)
		)
		(property "Val" "100n"
			(at 154.94 25.3935 90)
			(effects
				(font
					(size 1.27 1.27)
					(thickness 0.15)
				)
				(justify right)
			)
		)
		(property "License" "Apache-2.0"
			(at 175.26 6.35 0)
			(effects
				(font
					(size 1.27 1.27)
					(thickness 0.15)
				)
				(justify left bottom)
				(hide yes)
			)
		)
		(property "Author" "Antmicro"
			(at 177.8 6.35 0)
			(effects
				(font
					(size 1.27 1.27)
					(thickness 0.15)
				)
				(justify left bottom)
				(hide yes)
			)
		)
		(property "Voltage" "50V"
			(at 180.34 6.35 0)
			(effects
				(font
					(size 1.27 1.27)
				)
				(justify left bottom)
				(hide yes)
			)
		)
		(property "Dielectric" "X5R"
			(at 182.88 6.35 0)
			(effects
				(font
					(size 1.27 1.27)
				)
				(justify left bottom)
				(hide yes)
			)
		)
		(pin "1"
		)
		(pin "2"
		)
		(instances
			(project "k410t-devboard"
				(path ""
					(reference "C264")
					(unit 1)
				)
			)
		)
	)
	(symbol
		(lib_id "antmicropower:GND")
		(at 247.65 163.83 0)
		(unit 1)
		(exclude_from_sim no)
		(in_bom yes)
		(on_board yes)
		(dnp no)
		(property "Reference" "#PWR0323"
			(at 247.65 170.18 0)
			(effects
				(font
					(size 1.27 1.27)
				)
				(hide yes)
			)
		)
		(property "Value" "GND"
			(at 247.65 167.64 0)
			(effects
				(font
					(size 1.27 1.27)
				)
			)
		)
		(property "Footprint" ""
			(at 256.54 171.45 0)
			(effects
				(font
					(size 1.27 1.27)
					(thickness 0.15)
				)
				(justify left bottom)
				(hide yes)
			)
		)
		(property "Datasheet" ""
			(at 256.54 176.53 0)
			(effects
				(font
					(size 1.27 1.27)
					(thickness 0.15)
				)
				(justify left bottom)
				(hide yes)
			)
		)
		(property "Description" ""
			(at 247.65 163.83 0)
			(effects
				(font
					(size 1.27 1.27)
				)
			)
		)
		(property "Author" "Antmicro"
			(at 256.54 171.45 0)
			(effects
				(font
					(size 1.27 1.27)
					(thickness 0.15)
				)
				(justify left bottom)
				(hide yes)
			)
		)
		(property "License" "Apache-2.0"
			(at 256.54 173.99 0)
			(effects
				(font
					(size 1.27 1.27)
					(thickness 0.15)
				)
				(justify left bottom)
				(hide yes)
			)
		)
		(pin "1"
		)
		(instances
			(project "k410t-devboard"
				(path ""
					(reference "#PWR0323")
					(unit 1)
				)
			)
		)
	)
	(symbol
		(lib_id "antmicropower:PWR_FLAG")
		(at 327.66 35.56 270)
		(unit 1)
		(exclude_from_sim no)
		(in_bom yes)
		(on_board yes)
		(dnp no)
		(fields_autoplaced yes)
		(property "Reference" "#FLG012"
			(at 329.565 35.56 0)
			(effects
				(font
					(size 1.27 1.27)
				)
				(hide yes)
			)
		)
		(property "Value" "PWR_FLAG"
			(at 330.835 35.5599 90)
			(effects
				(font
					(size 1.27 1.27)
				)
				(justify left)
			)
		)
		(property "Footprint" ""
			(at 327.66 35.56 0)
			(effects
				(font
					(size 1.27 1.27)
				)
				(hide yes)
			)
		)
		(property "Datasheet" ""
			(at 327.66 35.56 0)
			(effects
				(font
					(size 1.27 1.27)
				)
				(hide yes)
			)
		)
		(property "Description" ""
			(at 327.66 35.56 0)
			(effects
				(font
					(size 1.27 1.27)
				)
			)
		)
		(pin "1"
		)
		(instances
			(project "k410t-devboard"
				(path ""
					(reference "#FLG012")
					(unit 1)
				)
			)
		)
	)
	(symbol
		(lib_id "antmicroInterfaceControllers:KSZ9131RNXC")
		(at 175.26 38.1 0)
		(unit 1)
		(exclude_from_sim no)
		(in_bom yes)
		(on_board yes)
		(dnp no)
		(fields_autoplaced yes)
		(property "Reference" "U27"
			(at 197.485 30.48 0)
			(effects
				(font
					(size 1.27 1.27)
				)
			)
		)
		(property "Value" "KSZ9131RNXC"
			(at 197.485 33.655 0)
			(effects
				(font
					(size 1.27 1.27)
					(thickness 0.15)
				)
				(hide yes)
			)
		)
		(property "Footprint" "antmicro-footprints:QFN-48-1EP_7x7x0.9mm_P0.5mm_EP5x5mm"
			(at 233.68 45.72 0)
			(effects
				(font
					(size 1.27 1.27)
					(thickness 0.15)
				)
				(justify left bottom)
				(hide yes)
			)
		)
		(property "Datasheet" "https://ww1.microchip.com/downloads/en/DeviceDoc/00002841B.pdf"
			(at 233.68 48.26 0)
			(effects
				(font
					(size 1.27 1.27)
					(thickness 0.15)
				)
				(justify left bottom)
				(hide yes)
			)
		)
		(property "Description" ""
			(at 175.26 38.1 0)
			(effects
				(font
					(size 1.27 1.27)
				)
			)
		)
		(property "Manufacturer" "Microchip Technology"
			(at 233.68 50.8 0)
			(effects
				(font
					(size 1.27 1.27)
					(thickness 0.15)
				)
				(justify left bottom)
				(hide yes)
			)
		)
		(property "MPN" "KSZ9131RNXC"
			(at 197.485 33.02 0)
			(effects
				(font
					(size 1.27 1.27)
					(thickness 0.15)
				)
			)
		)
		(property "Author" "Antmicro"
			(at 233.68 55.88 0)
			(effects
				(font
					(size 1.27 1.27)
					(thickness 0.15)
				)
				(justify left bottom)
				(hide yes)
			)
		)
		(property "License" "Apache-2.0"
			(at 233.68 58.42 0)
			(effects
				(font
					(size 1.27 1.27)
					(thickness 0.15)
				)
				(justify left bottom)
				(hide yes)
			)
		)
		(pin "1"
		)
		(pin "10"
		)
		(pin "11"
		)
		(pin "12"
		)
		(pin "13"
		)
		(pin "14"
		)
		(pin "15"
		)
		(pin "16"
		)
		(pin "17"
		)
		(pin "18"
		)
		(pin "19"
		)
		(pin "2"
		)
		(pin "20"
		)
		(pin "21"
		)
		(pin "22"
		)
		(pin "23"
		)
		(pin "24"
		)
		(pin "25"
		)
		(pin "26"
		)
		(pin "27"
		)
		(pin "28"
		)
		(pin "29"
		)
		(pin "3"
		)
		(pin "30"
		)
		(pin "31"
		)
		(pin "32"
		)
		(pin "33"
		)
		(pin "34"
		)
		(pin "35"
		)
		(pin "36"
		)
		(pin "37"
		)
		(pin "38"
		)
		(pin "39"
		)
		(pin "4"
		)
		(pin "40"
		)
		(pin "41"
		)
		(pin "42"
		)
		(pin "43"
		)
		(pin "44"
		)
		(pin "45"
		)
		(pin "46"
		)
		(pin "47"
		)
		(pin "48"
		)
		(pin "49"
		)
		(pin "5"
		)
		(pin "6"
		)
		(pin "7"
		)
		(pin "8"
		)
		(pin "9"
		)
		(instances
			(project "k410t-devboard"
				(path ""
					(reference "U27")
					(unit 1)
				)
			)
		)
	)
	(symbol
		(lib_id "antmicroResistors0402:R_10k_0402")
		(at 52.07 67.31 0)
		(mirror x)
		(unit 1)
		(exclude_from_sim no)
		(in_bom no)
		(on_board yes)
		(dnp yes)
		(property "Reference" "R203"
			(at 59.69 66.04 0)
			(effects
				(font
					(size 1.27 1.27)
				)
			)
		)
		(property "Value" "R_10k_0402"
			(at 72.39 54.61 0)
			(effects
				(font
					(size 1.27 1.27)
					(thickness 0.15)
				)
				(justify left bottom)
				(hide yes)
			)
		)
		(property "Footprint" "antmicro-footprints:R_0402_1005Metric"
			(at 72.39 52.07 0)
			(effects
				(font
					(size 1.27 1.27)
					(thickness 0.15)
				)
				(justify left bottom)
				(hide yes)
			)
		)
		(property "Datasheet" "https://www.bourns.com/docs/product-datasheets/cr.pdf"
			(at 72.39 49.53 0)
			(effects
				(font
					(size 1.27 1.27)
					(thickness 0.15)
				)
				(justify left bottom)
				(hide yes)
			)
		)
		(property "Description" ""
			(at 52.07 67.31 0)
			(effects
				(font
					(size 1.27 1.27)
				)
			)
		)
		(property "Manufacturer" "Bourns"
			(at 72.39 44.45 0)
			(effects
				(font
					(size 1.27 1.27)
					(thickness 0.15)
				)
				(justify left bottom)
				(hide yes)
			)
		)
		(property "MPN" "CR0402-FX-1002GLF"
			(at 72.39 46.99 0)
			(effects
				(font
					(size 1.27 1.27)
					(thickness 0.15)
				)
				(justify left bottom)
				(hide yes)
			)
		)
		(property "Val" "10k"
			(at 50.165 66.04 0)
			(effects
				(font
					(size 1.27 1.27)
					(thickness 0.15)
				)
			)
		)
		(property "DNP" "DNP"
			(at 54.61 67.31 0)
			(effects
				(font
					(size 1.27 1.27)
				)
			)
		)
		(property "License" "Apache-2.0"
			(at 72.39 41.91 0)
			(effects
				(font
					(size 1.27 1.27)
					(thickness 0.15)
				)
				(justify left bottom)
				(hide yes)
			)
		)
		(property "Author" "Antmicro"
			(at 72.39 39.37 0)
			(effects
				(font
					(size 1.27 1.27)
					(thickness 0.15)
				)
				(justify left bottom)
				(hide yes)
			)
		)
		(property "Tolerance" "1%"
			(at 72.39 57.15 0)
			(effects
				(font
					(size 1.27 1.27)
				)
				(justify left bottom)
				(hide yes)
			)
		)
		(pin "1"
		)
		(pin "2"
		)
		(instances
			(project "k410t-devboard"
				(path ""
					(reference "R203")
					(unit 1)
				)
			)
		)
	)
	(symbol
		(lib_id "antmicroModularConnectorsJacksWithMagnetics:0895-2C1R-GVH")
		(at 217.17 234.95 0)
		(unit 1)
		(exclude_from_sim no)
		(in_bom yes)
		(on_board yes)
		(dnp no)
		(fields_autoplaced yes)
		(property "Reference" "J15"
			(at 230.9205 227.33 0)
			(effects
				(font
					(size 1.27 1.27)
				)
			)
		)
		(property "Value" "0895-2C1R-GVH"
			(at 230.8975 229.235 0)
			(effects
				(font
					(size 1.27 1.27)
					(thickness 0.15)
				)
				(hide yes)
			)
		)
		(property "Footprint" "antmicro-footprints:0895-2C1R-GVH"
			(at 257.81 242.57 0)
			(effects
				(font
					(size 1.27 1.27)
					(thickness 0.15)
				)
				(justify left bottom)
				(hide yes)
			)
		)
		(property "Datasheet" "https://www.belfuse.com/resources/drawings/magneticsolutions/dr-mag-0895-2c1r-gvh.pdf"
			(at 257.81 245.11 0)
			(effects
				(font
					(size 1.27 1.27)
					(thickness 0.15)
				)
				(justify left bottom)
				(hide yes)
			)
		)
		(property "Description" ""
			(at 217.17 234.95 0)
			(effects
				(font
					(size 1.27 1.27)
				)
			)
		)
		(property "MPN" "0895-2C1R-GVH"
			(at 230.9205 229.87 0)
			(effects
				(font
					(size 1.27 1.27)
					(thickness 0.15)
				)
			)
		)
		(property "Manufacturer" "Bel Fuse"
			(at 257.81 250.19 0)
			(effects
				(font
					(size 1.27 1.27)
					(thickness 0.15)
				)
				(justify left bottom)
				(hide yes)
			)
		)
		(property "Author" "Antmicro"
			(at 257.81 252.73 0)
			(effects
				(font
					(size 1.27 1.27)
					(thickness 0.15)
				)
				(justify left bottom)
				(hide yes)
			)
		)
		(property "License" "Apache-2.0"
			(at 257.81 255.27 0)
			(effects
				(font
					(size 1.27 1.27)
					(thickness 0.15)
				)
				(justify left bottom)
				(hide yes)
			)
		)
		(pin "10_1"
		)
		(pin "11_1"
		)
		(pin "12_1"
		)
		(pin "13_1"
		)
		(pin "14_1"
		)
		(pin "15_1"
		)
		(pin "16_1"
		)
		(pin "17_1"
		)
		(pin "18_1"
		)
		(pin "1_1"
		)
		(pin "2_1"
		)
		(pin "3_1"
		)
		(pin "4_1"
		)
		(pin "5_1"
		)
		(pin "6_1"
		)
		(pin "7_1"
		)
		(pin "8_1"
		)
		(pin "9_1"
		)
		(pin "SH"
		)
		(pin "10_2"
		)
		(pin "11_2"
		)
		(pin "12_2"
		)
		(pin "13_2"
		)
		(pin "14_2"
		)
		(pin "15_2"
		)
		(pin "16_2"
		)
		(pin "17_2"
		)
		(pin "18_2"
		)
		(pin "1_2"
		)
		(pin "2_2"
		)
		(pin "3_2"
		)
		(pin "4_2"
		)
		(pin "5_2"
		)
		(pin "6_2"
		)
		(pin "7_2"
		)
		(pin "8_2"
		)
		(pin "9_2"
		)
		(pin "SH"
		)
		(pin "SH"
		)
		(pin "SH"
		)
		(pin "SH"
		)
		(pin "SH"
		)
		(instances
			(project "k410t-devboard"
				(path ""
					(reference "J15")
					(unit 1)
				)
			)
		)
	)
	(symbol
		(lib_id "antmicroResonators:Resonator_25MHz_ABM8G")
		(at 115.57 229.87 0)
		(unit 1)
		(exclude_from_sim no)
		(in_bom yes)
		(on_board yes)
		(dnp no)
		(property "Reference" "Y3"
			(at 119.38 223.52 0)
			(effects
				(font
					(size 1.27 1.27)
				)
			)
		)
		(property "Value" "Resonator_25MHz_ABM8G"
			(at 130.81 242.57 0)
			(effects
				(font
					(size 1.27 1.27)
					(thickness 0.15)
				)
				(justify left bottom)
				(hide yes)
			)
		)
		(property "Footprint" "antmicro-footprints:Resonator_SMD_Abracon_ABM8G_3.2x2.5mm"
			(at 130.81 245.11 0)
			(effects
				(font
					(size 1.27 1.27)
					(thickness 0.15)
				)
				(justify left bottom)
				(hide yes)
			)
		)
		(property "Datasheet" "https://abracon.com/Resonators/ABM8G.pdf"
			(at 130.81 247.65 0)
			(effects
				(font
					(size 1.27 1.27)
					(thickness 0.15)
				)
				(justify left bottom)
				(hide yes)
			)
		)
		(property "Description" ""
			(at 115.57 229.87 0)
			(effects
				(font
					(size 1.27 1.27)
				)
			)
		)
		(property "MPN" "ABM8G-25.000MHZ-18-D2Y-T3"
			(at 130.81 237.49 0)
			(effects
				(font
					(size 1.27 1.27)
					(thickness 0.15)
				)
				(justify left bottom)
				(hide yes)
			)
		)
		(property "Manufacturer" "Abracon"
			(at 130.81 250.19 0)
			(effects
				(font
					(size 1.27 1.27)
					(thickness 0.15)
				)
				(justify left bottom)
				(hide yes)
			)
		)
		(property "Val" "25 MHz"
			(at 119.38 226.06 0)
			(effects
				(font
					(size 1.27 1.27)
					(thickness 0.15)
				)
			)
		)
		(property "Author" "Antmicro"
			(at 130.81 252.73 0)
			(effects
				(font
					(size 1.27 1.27)
					(thickness 0.15)
				)
				(justify left bottom)
				(hide yes)
			)
		)
		(property "License" "Apache-2.0"
			(at 130.81 255.27 0)
			(effects
				(font
					(size 1.27 1.27)
					(thickness 0.15)
				)
				(justify left bottom)
				(hide yes)
			)
		)
		(pin "1"
		)
		(pin "2"
		)
		(pin "3"
		)
		(pin "4"
		)
		(instances
			(project "k410t-devboard"
				(path ""
					(reference "Y3")
					(unit 1)
				)
			)
		)
	)
	(symbol
		(lib_id "antmicroCapacitors0402:C_100n_0402")
		(at 142.24 43.18 90)
		(unit 1)
		(exclude_from_sim no)
		(in_bom yes)
		(on_board yes)
		(dnp no)
		(fields_autoplaced yes)
		(property "Reference" "C262"
			(at 145.415 39.3635 90)
			(effects
				(font
					(size 1.27 1.27)
				)
				(justify right)
			)
		)
		(property "Value" "C_100n_0402"
			(at 152.4 22.86 0)
			(effects
				(font
					(size 1.27 1.27)
					(thickness 0.15)
				)
				(justify left bottom)
				(hide yes)
			)
		)
		(property "Footprint" "antmicro-footprints:C_0402_1005Metric"
			(at 154.94 22.86 0)
			(effects
				(font
					(size 1.27 1.27)
					(thickness 0.15)
				)
				(justify left bottom)
				(hide yes)
			)
		)
		(property "Datasheet" "https://www.murata.com/products/productdetail?partno=GRM155R61H104KE14%23"
			(at 157.48 22.86 0)
			(effects
				(font
					(size 1.27 1.27)
					(thickness 0.15)
				)
				(justify left bottom)
				(hide yes)
			)
		)
		(property "Description" ""
			(at 142.24 43.18 0)
			(effects
				(font
					(size 1.27 1.27)
				)
			)
		)
		(property "Manufacturer" "Murata"
			(at 162.56 22.86 0)
			(effects
				(font
					(size 1.27 1.27)
					(thickness 0.15)
				)
				(justify left bottom)
				(hide yes)
			)
		)
		(property "MPN" "GRM155R61H104KE14D"
			(at 160.02 22.86 0)
			(effects
				(font
					(size 1.27 1.27)
					(thickness 0.15)
				)
				(justify left bottom)
				(hide yes)
			)
		)
		(property "Val" "100n"
			(at 145.415 41.9035 90)
			(effects
				(font
					(size 1.27 1.27)
					(thickness 0.15)
				)
				(justify right)
			)
		)
		(property "License" "Apache-2.0"
			(at 165.1 22.86 0)
			(effects
				(font
					(size 1.27 1.27)
					(thickness 0.15)
				)
				(justify left bottom)
				(hide yes)
			)
		)
		(property "Author" "Antmicro"
			(at 167.64 22.86 0)
			(effects
				(font
					(size 1.27 1.27)
					(thickness 0.15)
				)
				(justify left bottom)
				(hide yes)
			)
		)
		(property "Voltage" "50V"
			(at 170.18 22.86 0)
			(effects
				(font
					(size 1.27 1.27)
				)
				(justify left bottom)
				(hide yes)
			)
		)
		(property "Dielectric" "X5R"
			(at 172.72 22.86 0)
			(effects
				(font
					(size 1.27 1.27)
				)
				(justify left bottom)
				(hide yes)
			)
		)
		(pin "1"
		)
		(pin "2"
		)
		(instances
			(project "k410t-devboard"
				(path ""
					(reference "C262")
					(unit 1)
				)
			)
		)
	)
	(symbol
		(lib_id "antmicroCapacitors0402:C_100n_0402")
		(at 259.08 179.07 180)
		(unit 1)
		(exclude_from_sim no)
		(in_bom yes)
		(on_board yes)
		(dnp no)
		(property "Reference" "C283"
			(at 260.35 177.8 0)
			(effects
				(font
					(size 1.27 1.27)
				)
			)
		)
		(property "Value" "C_100n_0402"
			(at 238.76 168.91 0)
			(effects
				(font
					(size 1.27 1.27)
					(thickness 0.15)
				)
				(justify left bottom)
				(hide yes)
			)
		)
		(property "Footprint" "antmicro-footprints:C_0402_1005Metric"
			(at 238.76 166.37 0)
			(effects
				(font
					(size 1.27 1.27)
					(thickness 0.15)
				)
				(justify left bottom)
				(hide yes)
			)
		)
		(property "Datasheet" "https://www.murata.com/products/productdetail?partno=GRM155R61H104KE14%23"
			(at 238.76 163.83 0)
			(effects
				(font
					(size 1.27 1.27)
					(thickness 0.15)
				)
				(justify left bottom)
				(hide yes)
			)
		)
		(property "Description" ""
			(at 259.08 179.07 0)
			(effects
				(font
					(size 1.27 1.27)
				)
			)
		)
		(property "Manufacturer" "Murata"
			(at 238.76 158.75 0)
			(effects
				(font
					(size 1.27 1.27)
					(thickness 0.15)
				)
				(justify left bottom)
				(hide yes)
			)
		)
		(property "MPN" "GRM155R61H104KE14D"
			(at 238.76 161.29 0)
			(effects
				(font
					(size 1.27 1.27)
					(thickness 0.15)
				)
				(justify left bottom)
				(hide yes)
			)
		)
		(property "Val" "100n"
			(at 252.73 177.8 0)
			(effects
				(font
					(size 1.27 1.27)
					(thickness 0.15)
				)
			)
		)
		(property "License" "Apache-2.0"
			(at 238.76 156.21 0)
			(effects
				(font
					(size 1.27 1.27)
					(thickness 0.15)
				)
				(justify left bottom)
				(hide yes)
			)
		)
		(property "Author" "Antmicro"
			(at 238.76 153.67 0)
			(effects
				(font
					(size 1.27 1.27)
					(thickness 0.15)
				)
				(justify left bottom)
				(hide yes)
			)
		)
		(property "Voltage" "50V"
			(at 238.76 151.13 0)
			(effects
				(font
					(size 1.27 1.27)
				)
				(justify left bottom)
				(hide yes)
			)
		)
		(property "Dielectric" "X5R"
			(at 238.76 148.59 0)
			(effects
				(font
					(size 1.27 1.27)
				)
				(justify left bottom)
				(hide yes)
			)
		)
		(pin "1"
		)
		(pin "2"
		)
		(instances
			(project "k410t-devboard"
				(path ""
					(reference "C283")
					(unit 1)
				)
			)
		)
	)
	(symbol
		(lib_id "antmicroResistors0402:R_10R_0402")
		(at 81.28 190.5 0)
		(unit 1)
		(exclude_from_sim no)
		(in_bom yes)
		(on_board yes)
		(dnp no)
		(property "Reference" "R232"
			(at 88.9 189.23 0)
			(effects
				(font
					(size 1.27 1.27)
				)
			)
		)
		(property "Value" "R_10R_0402"
			(at 101.6 203.2 0)
			(effects
				(font
					(size 1.27 1.27)
					(thickness 0.15)
				)
				(justify left bottom)
				(hide yes)
			)
		)
		(property "Footprint" "antmicro-footprints:R_0402_1005Metric"
			(at 101.6 205.74 0)
			(effects
				(font
					(size 1.27 1.27)
					(thickness 0.15)
				)
				(justify left bottom)
				(hide yes)
			)
		)
		(property "Datasheet" "https://www.bourns.com/docs/product-datasheets/cr.pdf"
			(at 101.6 208.28 0)
			(effects
				(font
					(size 1.27 1.27)
					(thickness 0.15)
				)
				(justify left bottom)
				(hide yes)
			)
		)
		(property "Description" ""
			(at 81.28 190.5 0)
			(effects
				(font
					(size 1.27 1.27)
				)
			)
		)
		(property "Manufacturer" "Bourns"
			(at 101.6 213.36 0)
			(effects
				(font
					(size 1.27 1.27)
					(thickness 0.15)
				)
				(justify left bottom)
				(hide yes)
			)
		)
		(property "MPN" "CR0402-FX-10R0GLF"
			(at 101.6 210.82 0)
			(effects
				(font
					(size 1.27 1.27)
					(thickness 0.15)
				)
				(justify left bottom)
				(hide yes)
			)
		)
		(property "Val" "10R"
			(at 79.375 189.23 0)
			(effects
				(font
					(size 1.27 1.27)
					(thickness 0.15)
				)
			)
		)
		(property "License" "Apache-2.0"
			(at 101.6 215.9 0)
			(effects
				(font
					(size 1.27 1.27)
					(thickness 0.15)
				)
				(justify left bottom)
				(hide yes)
			)
		)
		(property "Author" "Antmicro"
			(at 101.6 218.44 0)
			(effects
				(font
					(size 1.27 1.27)
					(thickness 0.15)
				)
				(justify left bottom)
				(hide yes)
			)
		)
		(property "Tolerance" "1%"
			(at 101.6 200.66 0)
			(effects
				(font
					(size 1.27 1.27)
				)
				(justify left bottom)
				(hide yes)
			)
		)
		(pin "1"
		)
		(pin "2"
		)
		(instances
			(project "k410t-devboard"
				(path ""
					(reference "R232")
					(unit 1)
				)
			)
		)
	)
	(symbol
		(lib_id "antmicroCapacitors0402:C_100n_0402")
		(at 312.42 166.37 90)
		(unit 1)
		(exclude_from_sim no)
		(in_bom yes)
		(on_board yes)
		(dnp no)
		(property "Reference" "C398"
			(at 318.135 161.925 90)
			(effects
				(font
					(size 1.27 1.27)
				)
				(justify left)
			)
		)
		(property "Value" "C_100n_0402"
			(at 322.58 146.05 0)
			(effects
				(font
					(size 1.27 1.27)
					(thickness 0.15)
				)
				(justify left bottom)
				(hide yes)
			)
		)
		(property "Footprint" "antmicro-footprints:C_0402_1005Metric"
			(at 325.12 146.05 0)
			(effects
				(font
					(size 1.27 1.27)
					(thickness 0.15)
				)
				(justify left bottom)
				(hide yes)
			)
		)
		(property "Datasheet" "https://www.murata.com/products/productdetail?partno=GRM155R61H104KE14%23"
			(at 327.66 146.05 0)
			(effects
				(font
					(size 1.27 1.27)
					(thickness 0.15)
				)
				(justify left bottom)
				(hide yes)
			)
		)
		(property "Description" ""
			(at 312.42 166.37 0)
			(effects
				(font
					(size 1.27 1.27)
				)
			)
		)
		(property "Manufacturer" "Murata"
			(at 332.74 146.05 0)
			(effects
				(font
					(size 1.27 1.27)
					(thickness 0.15)
				)
				(justify left bottom)
				(hide yes)
			)
		)
		(property "MPN" "GRM155R61H104KE14D"
			(at 330.2 146.05 0)
			(effects
				(font
					(size 1.27 1.27)
					(thickness 0.15)
				)
				(justify left bottom)
				(hide yes)
			)
		)
		(property "Val" "100n"
			(at 318.135 165.735 90)
			(effects
				(font
					(size 1.27 1.27)
					(thickness 0.15)
				)
				(justify left)
			)
		)
		(property "License" "Apache-2.0"
			(at 335.28 146.05 0)
			(effects
				(font
					(size 1.27 1.27)
					(thickness 0.15)
				)
				(justify left bottom)
				(hide yes)
			)
		)
		(property "Author" "Antmicro"
			(at 337.82 146.05 0)
			(effects
				(font
					(size 1.27 1.27)
					(thickness 0.15)
				)
				(justify left bottom)
				(hide yes)
			)
		)
		(property "Voltage" "50V"
			(at 340.36 146.05 0)
			(effects
				(font
					(size 1.27 1.27)
				)
				(justify left bottom)
				(hide yes)
			)
		)
		(property "Dielectric" "X5R"
			(at 342.9 146.05 0)
			(effects
				(font
					(size 1.27 1.27)
				)
				(justify left bottom)
				(hide yes)
			)
		)
		(pin "1"
		)
		(pin "2"
		)
		(instances
			(project "k410t-devboard"
				(path ""
					(reference "C398")
					(unit 1)
				)
			)
		)
	)
	(symbol
		(lib_id "antmicroResistors0402:R_49R9_0402")
		(at 208.28 186.69 90)
		(unit 1)
		(exclude_from_sim no)
		(in_bom yes)
		(on_board yes)
		(dnp no)
		(fields_autoplaced yes)
		(property "Reference" "R245"
			(at 210.82 182.8799 90)
			(effects
				(font
					(size 1.27 1.27)
				)
				(justify right)
			)
		)
		(property "Value" "R_49R9_0402"
			(at 220.98 166.37 0)
			(effects
				(font
					(size 1.27 1.27)
					(thickness 0.15)
				)
				(justify left bottom)
				(hide yes)
			)
		)
		(property "Footprint" "antmicro-footprints:R_0402_1005Metric"
			(at 223.52 166.37 0)
			(effects
				(font
					(size 1.27 1.27)
					(thickness 0.15)
				)
				(justify left bottom)
				(hide yes)
			)
		)
		(property "Datasheet" "https://www.bourns.com/docs/product-datasheets/cr.pdf"
			(at 226.06 166.37 0)
			(effects
				(font
					(size 1.27 1.27)
					(thickness 0.15)
				)
				(justify left bottom)
				(hide yes)
			)
		)
		(property "Description" ""
			(at 208.28 186.69 0)
			(effects
				(font
					(size 1.27 1.27)
				)
			)
		)
		(property "Manufacturer" "Bourns"
			(at 231.14 166.37 0)
			(effects
				(font
					(size 1.27 1.27)
					(thickness 0.15)
				)
				(justify left bottom)
				(hide yes)
			)
		)
		(property "MPN" "CR0402-FX-49R9GLF"
			(at 228.6 166.37 0)
			(effects
				(font
					(size 1.27 1.27)
					(thickness 0.15)
				)
				(justify left bottom)
				(hide yes)
			)
		)
		(property "Val" "49R9"
			(at 210.82 185.4199 90)
			(effects
				(font
					(size 1.27 1.27)
					(thickness 0.15)
				)
				(justify right)
			)
		)
		(property "License" "Apache-2.0"
			(at 233.68 166.37 0)
			(effects
				(font
					(size 1.27 1.27)
					(thickness 0.15)
				)
				(justify left bottom)
				(hide yes)
			)
		)
		(property "Author" "Antmicro"
			(at 236.22 166.37 0)
			(effects
				(font
					(size 1.27 1.27)
					(thickness 0.15)
				)
				(justify left bottom)
				(hide yes)
			)
		)
		(property "Tolerance" "1%"
			(at 218.44 166.37 0)
			(effects
				(font
					(size 1.27 1.27)
				)
				(justify left bottom)
				(hide yes)
			)
		)
		(pin "1"
		)
		(pin "2"
		)
		(instances
			(project "k410t-devboard"
				(path ""
					(reference "R245")
					(unit 1)
				)
			)
		)
	)
	(symbol
		(lib_id "antmicroTVSDiodes:TPD4E05U06QDQARQ1")
		(at 311.15 203.2 0)
		(unit 1)
		(exclude_from_sim no)
		(in_bom yes)
		(on_board yes)
		(dnp no)
		(fields_autoplaced yes)
		(property "Reference" "U28"
			(at 321.31 206.375 0)
			(effects
				(font
					(size 1.27 1.27)
				)
				(justify left)
			)
		)
		(property "Value" "TPD4E05U06QDQARQ1"
			(at 321.945 208.9149 0)
			(effects
				(font
					(size 1.27 1.27)
					(thickness 0.15)
				)
				(justify left)
				(hide yes)
			)
		)
		(property "Footprint" "antmicro-footprints:USON-10_2.5x1mm_P0.5mm"
			(at 335.28 208.28 0)
			(effects
				(font
					(size 1.27 1.27)
					(thickness 0.15)
				)
				(justify left bottom)
				(hide yes)
			)
		)
		(property "Datasheet" "https://www.ti.com/lit/ds/symlink/tpd4e05u06-q1.pdf?HQS=dis-mous-null-mousermode-dsf-pf-null-wwe&ts=1663591265741&ref_url=https%253A%252F%252Fwww.mouser.com%252F"
			(at 335.28 210.82 0)
			(effects
				(font
					(size 1.27 1.27)
					(thickness 0.15)
				)
				(justify left bottom)
				(hide yes)
			)
		)
		(property "Description" ""
			(at 311.15 203.2 0)
			(effects
				(font
					(size 1.27 1.27)
				)
			)
		)
		(property "Manufacturer" "Texas Instruments"
			(at 335.28 213.36 0)
			(effects
				(font
					(size 1.27 1.27)
					(thickness 0.15)
				)
				(justify left bottom)
				(hide yes)
			)
		)
		(property "MPN" "TPD4E05U06QDQARQ1"
			(at 321.31 208.915 0)
			(effects
				(font
					(size 1.27 1.27)
					(thickness 0.15)
				)
				(justify left)
			)
		)
		(property "Author" "Antmicro"
			(at 335.28 218.44 0)
			(effects
				(font
					(size 1.27 1.27)
					(thickness 0.15)
				)
				(justify left bottom)
				(hide yes)
			)
		)
		(property "License" "Apache-2.0"
			(at 335.28 220.98 0)
			(effects
				(font
					(size 1.27 1.27)
					(thickness 0.15)
				)
				(justify left bottom)
				(hide yes)
			)
		)
		(pin "1"
		)
		(pin "10"
		)
		(pin "2"
		)
		(pin "3"
		)
		(pin "4"
		)
		(pin "5"
		)
		(pin "6"
		)
		(pin "7"
		)
		(pin "8"
		)
		(pin "9"
		)
		(instances
			(project "k410t-devboard"
				(path ""
					(reference "U28")
					(unit 1)
				)
			)
		)
	)
	(symbol
		(lib_id "antmicroCapacitors0402:C_22p_0402")
		(at 106.68 238.76 90)
		(unit 1)
		(exclude_from_sim no)
		(in_bom yes)
		(on_board yes)
		(dnp no)
		(property "Reference" "C252"
			(at 107.315 234.315 90)
			(effects
				(font
					(size 1.27 1.27)
				)
				(justify right)
			)
		)
		(property "Value" "C_22p_0402"
			(at 116.84 218.44 0)
			(effects
				(font
					(size 1.27 1.27)
					(thickness 0.15)
				)
				(justify left bottom)
				(hide yes)
			)
		)
		(property "Footprint" "antmicro-footprints:C_0402_1005Metric"
			(at 119.38 218.44 0)
			(effects
				(font
					(size 1.27 1.27)
					(thickness 0.15)
				)
				(justify left bottom)
				(hide yes)
			)
		)
		(property "Datasheet" "https://www.yageo.com/en/Chart/Download/pdf/CC0402JRNPO9BN220"
			(at 121.92 218.44 0)
			(effects
				(font
					(size 1.27 1.27)
					(thickness 0.15)
				)
				(justify left bottom)
				(hide yes)
			)
		)
		(property "Description" ""
			(at 106.68 238.76 0)
			(effects
				(font
					(size 1.27 1.27)
				)
			)
		)
		(property "Manufacturer" "YAGEO"
			(at 127 218.44 0)
			(effects
				(font
					(size 1.27 1.27)
					(thickness 0.15)
				)
				(justify left bottom)
				(hide yes)
			)
		)
		(property "MPN" "CC0402JRNPO9BN220"
			(at 124.46 218.44 0)
			(effects
				(font
					(size 1.27 1.27)
					(thickness 0.15)
				)
				(justify left bottom)
				(hide yes)
			)
		)
		(property "Val" "22p"
			(at 107.315 238.125 90)
			(effects
				(font
					(size 1.27 1.27)
					(thickness 0.15)
				)
				(justify right)
			)
		)
		(property "License" "Apache-2.0"
			(at 129.54 218.44 0)
			(effects
				(font
					(size 1.27 1.27)
					(thickness 0.15)
				)
				(justify left bottom)
				(hide yes)
			)
		)
		(property "Author" "Antmicro"
			(at 132.08 218.44 0)
			(effects
				(font
					(size 1.27 1.27)
					(thickness 0.15)
				)
				(justify left bottom)
				(hide yes)
			)
		)
		(property "Voltage" ""
			(at 134.62 218.44 0)
			(effects
				(font
					(size 1.27 1.27)
				)
				(justify left bottom)
				(hide yes)
			)
		)
		(property "Dielectric" ""
			(at 137.16 218.44 0)
			(effects
				(font
					(size 1.27 1.27)
				)
				(justify left bottom)
				(hide yes)
			)
		)
		(pin "1"
		)
		(pin "2"
		)
		(instances
			(project "k410t-devboard"
				(path ""
					(reference "C252")
					(unit 1)
				)
			)
		)
	)
	(symbol
		(lib_id "antmicroResistors0402:R_10k_0402")
		(at 52.07 63.5 0)
		(mirror x)
		(unit 1)
		(exclude_from_sim no)
		(in_bom no)
		(on_board yes)
		(dnp yes)
		(property "Reference" "R202"
			(at 59.69 62.23 0)
			(effects
				(font
					(size 1.27 1.27)
				)
			)
		)
		(property "Value" "R_10k_0402"
			(at 72.39 50.8 0)
			(effects
				(font
					(size 1.27 1.27)
					(thickness 0.15)
				)
				(justify left bottom)
				(hide yes)
			)
		)
		(property "Footprint" "antmicro-footprints:R_0402_1005Metric"
			(at 72.39 48.26 0)
			(effects
				(font
					(size 1.27 1.27)
					(thickness 0.15)
				)
				(justify left bottom)
				(hide yes)
			)
		)
		(property "Datasheet" "https://www.bourns.com/docs/product-datasheets/cr.pdf"
			(at 72.39 45.72 0)
			(effects
				(font
					(size 1.27 1.27)
					(thickness 0.15)
				)
				(justify left bottom)
				(hide yes)
			)
		)
		(property "Description" ""
			(at 52.07 63.5 0)
			(effects
				(font
					(size 1.27 1.27)
				)
			)
		)
		(property "Manufacturer" "Bourns"
			(at 72.39 40.64 0)
			(effects
				(font
					(size 1.27 1.27)
					(thickness 0.15)
				)
				(justify left bottom)
				(hide yes)
			)
		)
		(property "MPN" "CR0402-FX-1002GLF"
			(at 72.39 43.18 0)
			(effects
				(font
					(size 1.27 1.27)
					(thickness 0.15)
				)
				(justify left bottom)
				(hide yes)
			)
		)
		(property "Val" "10k"
			(at 50.165 62.23 0)
			(effects
				(font
					(size 1.27 1.27)
					(thickness 0.15)
				)
			)
		)
		(property "DNP" "DNP"
			(at 54.61 63.5 0)
			(effects
				(font
					(size 1.27 1.27)
				)
			)
		)
		(property "License" "Apache-2.0"
			(at 72.39 38.1 0)
			(effects
				(font
					(size 1.27 1.27)
					(thickness 0.15)
				)
				(justify left bottom)
				(hide yes)
			)
		)
		(property "Author" "Antmicro"
			(at 72.39 35.56 0)
			(effects
				(font
					(size 1.27 1.27)
					(thickness 0.15)
				)
				(justify left bottom)
				(hide yes)
			)
		)
		(property "Tolerance" "1%"
			(at 72.39 53.34 0)
			(effects
				(font
					(size 1.27 1.27)
				)
				(justify left bottom)
				(hide yes)
			)
		)
		(pin "1"
		)
		(pin "2"
		)
		(instances
			(project "k410t-devboard"
				(path ""
					(reference "R202")
					(unit 1)
				)
			)
		)
	)
	(symbol
		(lib_id "antmicroCapacitors0402:C_100n_0402")
		(at 269.24 26.67 90)
		(unit 1)
		(exclude_from_sim no)
		(in_bom yes)
		(on_board yes)
		(dnp no)
		(property "Reference" "C286"
			(at 269.875 22.225 90)
			(effects
				(font
					(size 1.27 1.27)
				)
				(justify right)
			)
		)
		(property "Value" "C_100n_0402"
			(at 279.4 6.35 0)
			(effects
				(font
					(size 1.27 1.27)
					(thickness 0.15)
				)
				(justify left bottom)
				(hide yes)
			)
		)
		(property "Footprint" "antmicro-footprints:C_0402_1005Metric"
			(at 281.94 6.35 0)
			(effects
				(font
					(size 1.27 1.27)
					(thickness 0.15)
				)
				(justify left bottom)
				(hide yes)
			)
		)
		(property "Datasheet" "https://www.murata.com/products/productdetail?partno=GRM155R61H104KE14%23"
			(at 284.48 6.35 0)
			(effects
				(font
					(size 1.27 1.27)
					(thickness 0.15)
				)
				(justify left bottom)
				(hide yes)
			)
		)
		(property "Description" ""
			(at 269.24 26.67 0)
			(effects
				(font
					(size 1.27 1.27)
				)
			)
		)
		(property "Manufacturer" "Murata"
			(at 289.56 6.35 0)
			(effects
				(font
					(size 1.27 1.27)
					(thickness 0.15)
				)
				(justify left bottom)
				(hide yes)
			)
		)
		(property "MPN" "GRM155R61H104KE14D"
			(at 287.02 6.35 0)
			(effects
				(font
					(size 1.27 1.27)
					(thickness 0.15)
				)
				(justify left bottom)
				(hide yes)
			)
		)
		(property "Val" "100n"
			(at 269.875 26.035 90)
			(effects
				(font
					(size 1.27 1.27)
					(thickness 0.15)
				)
				(justify right)
			)
		)
		(property "License" "Apache-2.0"
			(at 292.1 6.35 0)
			(effects
				(font
					(size 1.27 1.27)
					(thickness 0.15)
				)
				(justify left bottom)
				(hide yes)
			)
		)
		(property "Author" "Antmicro"
			(at 294.64 6.35 0)
			(effects
				(font
					(size 1.27 1.27)
					(thickness 0.15)
				)
				(justify left bottom)
				(hide yes)
			)
		)
		(property "Voltage" "50V"
			(at 297.18 6.35 0)
			(effects
				(font
					(size 1.27 1.27)
				)
				(justify left bottom)
				(hide yes)
			)
		)
		(property "Dielectric" "X5R"
			(at 299.72 6.35 0)
			(effects
				(font
					(size 1.27 1.27)
				)
				(justify left bottom)
				(hide yes)
			)
		)
		(pin "1"
		)
		(pin "2"
		)
		(instances
			(project "k410t-devboard"
				(path ""
					(reference "C286")
					(unit 1)
				)
			)
		)
	)
	(symbol
		(lib_id "antmicroCapacitors0402:C_22n_0402")
		(at 237.49 43.18 90)
		(unit 1)
		(exclude_from_sim no)
		(in_bom yes)
		(on_board yes)
		(dnp no)
		(property "Reference" "C278"
			(at 238.125 38.735 90)
			(effects
				(font
					(size 1.27 1.27)
				)
				(justify right)
			)
		)
		(property "Value" "C_22n_0402"
			(at 247.65 22.86 0)
			(effects
				(font
					(size 1.27 1.27)
					(thickness 0.15)
				)
				(justify left bottom)
				(hide yes)
			)
		)
		(property "Footprint" "antmicro-footprints:C_0402_1005Metric"
			(at 250.19 22.86 0)
			(effects
				(font
					(size 1.27 1.27)
					(thickness 0.15)
				)
				(justify left bottom)
				(hide yes)
			)
		)
		(property "Datasheet" "https://www.murata.com/products/productdetail?partno=GCM155R71H223MA55%23"
			(at 252.73 22.86 0)
			(effects
				(font
					(size 1.27 1.27)
					(thickness 0.15)
				)
				(justify left bottom)
				(hide yes)
			)
		)
		(property "Description" ""
			(at 237.49 43.18 0)
			(effects
				(font
					(size 1.27 1.27)
				)
			)
		)
		(property "Manufacturer" "Murata"
			(at 257.81 22.86 0)
			(effects
				(font
					(size 1.27 1.27)
					(thickness 0.15)
				)
				(justify left bottom)
				(hide yes)
			)
		)
		(property "MPN" "GCM155R71H223MA55D"
			(at 255.27 22.86 0)
			(effects
				(font
					(size 1.27 1.27)
					(thickness 0.15)
				)
				(justify left bottom)
				(hide yes)
			)
		)
		(property "Val" "22n"
			(at 238.125 42.545 90)
			(effects
				(font
					(size 1.27 1.27)
					(thickness 0.15)
				)
				(justify right)
			)
		)
		(property "License" "Apache-2.0"
			(at 260.35 22.86 0)
			(effects
				(font
					(size 1.27 1.27)
					(thickness 0.15)
				)
				(justify left bottom)
				(hide yes)
			)
		)
		(property "Author" "Antmicro"
			(at 262.89 22.86 0)
			(effects
				(font
					(size 1.27 1.27)
					(thickness 0.15)
				)
				(justify left bottom)
				(hide yes)
			)
		)
		(property "Voltage" ""
			(at 265.43 22.86 0)
			(effects
				(font
					(size 1.27 1.27)
				)
				(justify left bottom)
				(hide yes)
			)
		)
		(property "Dielectric" ""
			(at 267.97 22.86 0)
			(effects
				(font
					(size 1.27 1.27)
				)
				(justify left bottom)
				(hide yes)
			)
		)
		(pin "1"
		)
		(pin "2"
		)
		(instances
			(project "k410t-devboard"
				(path ""
					(reference "C278")
					(unit 1)
				)
			)
		)
	)
	(symbol
		(lib_id "antmicropower:GND")
		(at 290.83 29.21 0)
		(mirror y)
		(unit 1)
		(exclude_from_sim no)
		(in_bom yes)
		(on_board yes)
		(dnp no)
		(fields_autoplaced yes)
		(property "Reference" "#PWR0338"
			(at 290.83 35.56 0)
			(effects
				(font
					(size 1.27 1.27)
				)
				(hide yes)
			)
		)
		(property "Value" "GND"
			(at 290.83 33.02 0)
			(effects
				(font
					(size 1.27 1.27)
				)
			)
		)
		(property "Footprint" ""
			(at 281.94 36.83 0)
			(effects
				(font
					(size 1.27 1.27)
					(thickness 0.15)
				)
				(justify left bottom)
				(hide yes)
			)
		)
		(property "Datasheet" ""
			(at 281.94 41.91 0)
			(effects
				(font
					(size 1.27 1.27)
					(thickness 0.15)
				)
				(justify left bottom)
				(hide yes)
			)
		)
		(property "Description" ""
			(at 290.83 29.21 0)
			(effects
				(font
					(size 1.27 1.27)
				)
			)
		)
		(property "Author" "Antmicro"
			(at 281.94 36.83 0)
			(effects
				(font
					(size 1.27 1.27)
					(thickness 0.15)
				)
				(justify left bottom)
				(hide yes)
			)
		)
		(property "License" "Apache-2.0"
			(at 281.94 39.37 0)
			(effects
				(font
					(size 1.27 1.27)
					(thickness 0.15)
				)
				(justify left bottom)
				(hide yes)
			)
		)
		(pin "1"
		)
		(instances
			(project "k410t-devboard"
				(path ""
					(reference "#PWR0338")
					(unit 1)
				)
			)
		)
	)
	(symbol
		(lib_id "antmicropower:+3.3V")
		(at 106.68 19.05 0)
		(unit 1)
		(exclude_from_sim no)
		(in_bom yes)
		(on_board yes)
		(dnp no)
		(fields_autoplaced yes)
		(property "Reference" "#PWR0256"
			(at 106.68 22.86 0)
			(effects
				(font
					(size 1.27 1.27)
				)
				(hide yes)
			)
		)
		(property "Value" "+3V3"
			(at 106.68 15.494 0)
			(effects
				(font
					(size 1.27 1.27)
				)
			)
		)
		(property "Footprint" ""
			(at 106.68 19.05 0)
			(effects
				(font
					(size 1.27 1.27)
				)
				(hide yes)
			)
		)
		(property "Datasheet" ""
			(at 106.68 19.05 0)
			(effects
				(font
					(size 1.27 1.27)
				)
				(hide yes)
			)
		)
		(property "Description" ""
			(at 106.68 19.05 0)
			(effects
				(font
					(size 1.27 1.27)
				)
			)
		)
		(pin "1"
		)
		(instances
			(project "k410t-devboard"
				(path ""
					(reference "#PWR0256")
					(unit 1)
				)
			)
		)
	)
	(symbol
		(lib_id "antmicropower:GND")
		(at 127 163.83 0)
		(unit 1)
		(exclude_from_sim no)
		(in_bom yes)
		(on_board yes)
		(dnp no)
		(property "Reference" "#PWR0292"
			(at 127 170.18 0)
			(effects
				(font
					(size 1.27 1.27)
				)
				(hide yes)
			)
		)
		(property "Value" "GND"
			(at 127 167.64 0)
			(effects
				(font
					(size 1.27 1.27)
				)
			)
		)
		(property "Footprint" ""
			(at 135.89 171.45 0)
			(effects
				(font
					(size 1.27 1.27)
					(thickness 0.15)
				)
				(justify left bottom)
				(hide yes)
			)
		)
		(property "Datasheet" ""
			(at 135.89 176.53 0)
			(effects
				(font
					(size 1.27 1.27)
					(thickness 0.15)
				)
				(justify left bottom)
				(hide yes)
			)
		)
		(property "Description" ""
			(at 127 163.83 0)
			(effects
				(font
					(size 1.27 1.27)
				)
			)
		)
		(property "Author" "Antmicro"
			(at 135.89 171.45 0)
			(effects
				(font
					(size 1.27 1.27)
					(thickness 0.15)
				)
				(justify left bottom)
				(hide yes)
			)
		)
		(property "License" "Apache-2.0"
			(at 135.89 173.99 0)
			(effects
				(font
					(size 1.27 1.27)
					(thickness 0.15)
				)
				(justify left bottom)
				(hide yes)
			)
		)
		(pin "1"
		)
		(instances
			(project "k410t-devboard"
				(path ""
					(reference "#PWR0292")
					(unit 1)
				)
			)
		)
	)
	(symbol
		(lib_id "antmicropower:GND")
		(at 124.46 132.08 0)
		(unit 1)
		(exclude_from_sim no)
		(in_bom yes)
		(on_board yes)
		(dnp no)
		(fields_autoplaced yes)
		(property "Reference" "#PWR0291"
			(at 124.46 138.43 0)
			(effects
				(font
					(size 1.27 1.27)
				)
				(hide yes)
			)
		)
		(property "Value" "GND"
			(at 124.46 135.89 0)
			(effects
				(font
					(size 1.27 1.27)
				)
			)
		)
		(property "Footprint" ""
			(at 133.35 139.7 0)
			(effects
				(font
					(size 1.27 1.27)
					(thickness 0.15)
				)
				(justify left bottom)
				(hide yes)
			)
		)
		(property "Datasheet" ""
			(at 133.35 144.78 0)
			(effects
				(font
					(size 1.27 1.27)
					(thickness 0.15)
				)
				(justify left bottom)
				(hide yes)
			)
		)
		(property "Description" ""
			(at 124.46 132.08 0)
			(effects
				(font
					(size 1.27 1.27)
				)
			)
		)
		(property "Author" "Antmicro"
			(at 133.35 139.7 0)
			(effects
				(font
					(size 1.27 1.27)
					(thickness 0.15)
				)
				(justify left bottom)
				(hide yes)
			)
		)
		(property "License" "Apache-2.0"
			(at 133.35 142.24 0)
			(effects
				(font
					(size 1.27 1.27)
					(thickness 0.15)
				)
				(justify left bottom)
				(hide yes)
			)
		)
		(pin "1"
		)
		(instances
			(project "k410t-devboard"
				(path ""
					(reference "#PWR0291")
					(unit 1)
				)
			)
		)
	)
	(symbol
		(lib_id "antmicroCapacitors0402:C_22p_0402")
		(at 129.54 238.76 90)
		(unit 1)
		(exclude_from_sim no)
		(in_bom yes)
		(on_board yes)
		(dnp no)
		(property "Reference" "C258"
			(at 130.175 234.315 90)
			(effects
				(font
					(size 1.27 1.27)
				)
				(justify right)
			)
		)
		(property "Value" "C_22p_0402"
			(at 139.7 218.44 0)
			(effects
				(font
					(size 1.27 1.27)
					(thickness 0.15)
				)
				(justify left bottom)
				(hide yes)
			)
		)
		(property "Footprint" "antmicro-footprints:C_0402_1005Metric"
			(at 142.24 218.44 0)
			(effects
				(font
					(size 1.27 1.27)
					(thickness 0.15)
				)
				(justify left bottom)
				(hide yes)
			)
		)
		(property "Datasheet" "https://www.yageo.com/en/Chart/Download/pdf/CC0402JRNPO9BN220"
			(at 144.78 218.44 0)
			(effects
				(font
					(size 1.27 1.27)
					(thickness 0.15)
				)
				(justify left bottom)
				(hide yes)
			)
		)
		(property "Description" ""
			(at 129.54 238.76 0)
			(effects
				(font
					(size 1.27 1.27)
				)
			)
		)
		(property "Manufacturer" "YAGEO"
			(at 149.86 218.44 0)
			(effects
				(font
					(size 1.27 1.27)
					(thickness 0.15)
				)
				(justify left bottom)
				(hide yes)
			)
		)
		(property "MPN" "CC0402JRNPO9BN220"
			(at 147.32 218.44 0)
			(effects
				(font
					(size 1.27 1.27)
					(thickness 0.15)
				)
				(justify left bottom)
				(hide yes)
			)
		)
		(property "Val" "22p"
			(at 130.175 238.125 90)
			(effects
				(font
					(size 1.27 1.27)
					(thickness 0.15)
				)
				(justify right)
			)
		)
		(property "License" "Apache-2.0"
			(at 152.4 218.44 0)
			(effects
				(font
					(size 1.27 1.27)
					(thickness 0.15)
				)
				(justify left bottom)
				(hide yes)
			)
		)
		(property "Author" "Antmicro"
			(at 154.94 218.44 0)
			(effects
				(font
					(size 1.27 1.27)
					(thickness 0.15)
				)
				(justify left bottom)
				(hide yes)
			)
		)
		(property "Voltage" ""
			(at 157.48 218.44 0)
			(effects
				(font
					(size 1.27 1.27)
				)
				(justify left bottom)
				(hide yes)
			)
		)
		(property "Dielectric" ""
			(at 160.02 218.44 0)
			(effects
				(font
					(size 1.27 1.27)
				)
				(justify left bottom)
				(hide yes)
			)
		)
		(pin "1"
		)
		(pin "2"
		)
		(instances
			(project "k410t-devboard"
				(path ""
					(reference "C258")
					(unit 1)
				)
			)
		)
	)
	(symbol
		(lib_id "antmicropower:+3.3V")
		(at 396.24 90.17 0)
		(unit 1)
		(exclude_from_sim no)
		(in_bom yes)
		(on_board yes)
		(dnp no)
		(property "Reference" "#PWR0316"
			(at 396.24 93.98 0)
			(effects
				(font
					(size 1.27 1.27)
				)
				(hide yes)
			)
		)
		(property "Value" "+3V3"
			(at 396.24 86.614 0)
			(effects
				(font
					(size 1.27 1.27)
				)
			)
		)
		(property "Footprint" ""
			(at 396.24 90.17 0)
			(effects
				(font
					(size 1.27 1.27)
				)
				(hide yes)
			)
		)
		(property "Datasheet" ""
			(at 396.24 90.17 0)
			(effects
				(font
					(size 1.27 1.27)
				)
				(hide yes)
			)
		)
		(property "Description" ""
			(at 396.24 90.17 0)
			(effects
				(font
					(size 1.27 1.27)
				)
			)
		)
		(pin "1"
		)
		(instances
			(project "k410t-devboard"
				(path ""
					(reference "#PWR0316")
					(unit 1)
				)
			)
		)
	)
	(symbol
		(lib_id "antmicroResistors0402:R_2k2_0402")
		(at 52.07 264.16 0)
		(unit 1)
		(exclude_from_sim no)
		(in_bom yes)
		(on_board yes)
		(dnp no)
		(property "Reference" "R229"
			(at 59.69 262.89 0)
			(effects
				(font
					(size 1.27 1.27)
				)
			)
		)
		(property "Value" "R_2k2_0402"
			(at 72.39 276.86 0)
			(effects
				(font
					(size 1.27 1.27)
					(thickness 0.15)
				)
				(justify left bottom)
				(hide yes)
			)
		)
		(property "Footprint" "antmicro-footprints:R_0402_1005Metric"
			(at 72.39 279.4 0)
			(effects
				(font
					(size 1.27 1.27)
					(thickness 0.15)
				)
				(justify left bottom)
				(hide yes)
			)
		)
		(property "Datasheet" "https://www.bourns.com/docs/product-datasheets/cr.pdf"
			(at 72.39 281.94 0)
			(effects
				(font
					(size 1.27 1.27)
					(thickness 0.15)
				)
				(justify left bottom)
				(hide yes)
			)
		)
		(property "Description" ""
			(at 52.07 264.16 0)
			(effects
				(font
					(size 1.27 1.27)
				)
			)
		)
		(property "Manufacturer" "Bourns"
			(at 72.39 287.02 0)
			(effects
				(font
					(size 1.27 1.27)
					(thickness 0.15)
				)
				(justify left bottom)
				(hide yes)
			)
		)
		(property "MPN" "CR0402-FX-2201GLF"
			(at 72.39 284.48 0)
			(effects
				(font
					(size 1.27 1.27)
					(thickness 0.15)
				)
				(justify left bottom)
				(hide yes)
			)
		)
		(property "Val" "2k2"
			(at 50.165 262.89 0)
			(effects
				(font
					(size 1.27 1.27)
					(thickness 0.15)
				)
			)
		)
		(property "License" "Apache-2.0"
			(at 72.39 289.56 0)
			(effects
				(font
					(size 1.27 1.27)
					(thickness 0.15)
				)
				(justify left bottom)
				(hide yes)
			)
		)
		(property "Author" "Antmicro"
			(at 72.39 292.1 0)
			(effects
				(font
					(size 1.27 1.27)
					(thickness 0.15)
				)
				(justify left bottom)
				(hide yes)
			)
		)
		(property "Tolerance" "1%"
			(at 72.39 274.32 0)
			(effects
				(font
					(size 1.27 1.27)
				)
				(justify left bottom)
				(hide yes)
			)
		)
		(pin "1"
		)
		(pin "2"
		)
		(instances
			(project "k410t-devboard"
				(path ""
					(reference "R229")
					(unit 1)
				)
			)
		)
	)
	(symbol
		(lib_id "antmicropower:GND")
		(at 142.24 44.45 0)
		(mirror y)
		(unit 1)
		(exclude_from_sim no)
		(in_bom yes)
		(on_board yes)
		(dnp no)
		(fields_autoplaced yes)
		(property "Reference" "#PWR0301"
			(at 142.24 50.8 0)
			(effects
				(font
					(size 1.27 1.27)
				)
				(hide yes)
			)
		)
		(property "Value" "GND"
			(at 142.24 48.26 0)
			(effects
				(font
					(size 1.27 1.27)
				)
			)
		)
		(property "Footprint" ""
			(at 133.35 52.07 0)
			(effects
				(font
					(size 1.27 1.27)
					(thickness 0.15)
				)
				(justify left bottom)
				(hide yes)
			)
		)
		(property "Datasheet" ""
			(at 133.35 57.15 0)
			(effects
				(font
					(size 1.27 1.27)
					(thickness 0.15)
				)
				(justify left bottom)
				(hide yes)
			)
		)
		(property "Description" ""
			(at 142.24 44.45 0)
			(effects
				(font
					(size 1.27 1.27)
				)
			)
		)
		(property "Author" "Antmicro"
			(at 133.35 52.07 0)
			(effects
				(font
					(size 1.27 1.27)
					(thickness 0.15)
				)
				(justify left bottom)
				(hide yes)
			)
		)
		(property "License" "Apache-2.0"
			(at 133.35 54.61 0)
			(effects
				(font
					(size 1.27 1.27)
					(thickness 0.15)
				)
				(justify left bottom)
				(hide yes)
			)
		)
		(pin "1"
		)
		(instances
			(project "k410t-devboard"
				(path ""
					(reference "#PWR0301")
					(unit 1)
				)
			)
		)
	)
	(symbol
		(lib_id "antmicroCapacitors0402:C_10u_0402")
		(at 317.5 26.67 90)
		(unit 1)
		(exclude_from_sim no)
		(in_bom yes)
		(on_board yes)
		(dnp no)
		(property "Reference" "C292"
			(at 318.135 22.225 90)
			(effects
				(font
					(size 1.27 1.27)
				)
				(justify right)
			)
		)
		(property "Value" "C_10u_0402"
			(at 327.66 6.35 0)
			(effects
				(font
					(size 1.27 1.27)
					(thickness 0.15)
				)
				(justify left bottom)
				(hide yes)
			)
		)
		(property "Footprint" "antmicro-footprints:C_0402_1005Metric"
			(at 330.2 6.35 0)
			(effects
				(font
					(size 1.27 1.27)
					(thickness 0.15)
				)
				(justify left bottom)
				(hide yes)
			)
		)
		(property "Datasheet" "https://www.yageo.com/en/Chart/Download/pdf/CC0402MRX5R5BB106"
			(at 332.74 6.35 0)
			(effects
				(font
					(size 1.27 1.27)
					(thickness 0.15)
				)
				(justify left bottom)
				(hide yes)
			)
		)
		(property "Description" ""
			(at 317.5 26.67 0)
			(effects
				(font
					(size 1.27 1.27)
				)
			)
		)
		(property "Manufacturer" "YAGEO"
			(at 337.82 6.35 0)
			(effects
				(font
					(size 1.27 1.27)
					(thickness 0.15)
				)
				(justify left bottom)
				(hide yes)
			)
		)
		(property "MPN" "CC0402MRX5R5BB106"
			(at 335.28 6.35 0)
			(effects
				(font
					(size 1.27 1.27)
					(thickness 0.15)
				)
				(justify left bottom)
				(hide yes)
			)
		)
		(property "Val" "10u"
			(at 318.135 26.035 90)
			(effects
				(font
					(size 1.27 1.27)
					(thickness 0.15)
				)
				(justify right)
			)
		)
		(property "License" "Apache-2.0"
			(at 340.36 6.35 0)
			(effects
				(font
					(size 1.27 1.27)
					(thickness 0.15)
				)
				(justify left bottom)
				(hide yes)
			)
		)
		(property "Author" "Antmicro"
			(at 342.9 6.35 0)
			(effects
				(font
					(size 1.27 1.27)
					(thickness 0.15)
				)
				(justify left bottom)
				(hide yes)
			)
		)
		(property "Voltage" ""
			(at 345.44 6.35 0)
			(effects
				(font
					(size 1.27 1.27)
				)
				(justify left bottom)
				(hide yes)
			)
		)
		(property "Dielectric" ""
			(at 347.98 6.35 0)
			(effects
				(font
					(size 1.27 1.27)
				)
				(justify left bottom)
				(hide yes)
			)
		)
		(pin "1"
		)
		(pin "2"
		)
		(instances
			(project "k410t-devboard"
				(path ""
					(reference "C292")
					(unit 1)
				)
			)
		)
	)
	(symbol
		(lib_id "antmicropower:PWR_FLAG")
		(at 356.87 157.48 270)
		(unit 1)
		(exclude_from_sim no)
		(in_bom yes)
		(on_board yes)
		(dnp no)
		(fields_autoplaced yes)
		(property "Reference" "#FLG014"
			(at 358.775 157.48 0)
			(effects
				(font
					(size 1.27 1.27)
				)
				(hide yes)
			)
		)
		(property "Value" "PWR_FLAG"
			(at 360.68 157.4799 90)
			(effects
				(font
					(size 1.27 1.27)
				)
				(justify left)
			)
		)
		(property "Footprint" ""
			(at 356.87 157.48 0)
			(effects
				(font
					(size 1.27 1.27)
				)
				(hide yes)
			)
		)
		(property "Datasheet" ""
			(at 356.87 157.48 0)
			(effects
				(font
					(size 1.27 1.27)
				)
				(hide yes)
			)
		)
		(property "Description" ""
			(at 356.87 157.48 0)
			(effects
				(font
					(size 1.27 1.27)
				)
			)
		)
		(pin "1"
		)
		(instances
			(project "k410t-devboard"
				(path ""
					(reference "#FLG014")
					(unit 1)
				)
			)
		)
	)
	(symbol
		(lib_id "antmicropower:GND")
		(at 152.4 44.45 0)
		(mirror y)
		(unit 1)
		(exclude_from_sim no)
		(in_bom yes)
		(on_board yes)
		(dnp no)
		(fields_autoplaced yes)
		(property "Reference" "#PWR0304"
			(at 152.4 50.8 0)
			(effects
				(font
					(size 1.27 1.27)
				)
				(hide yes)
			)
		)
		(property "Value" "GND"
			(at 152.4 48.26 0)
			(effects
				(font
					(size 1.27 1.27)
				)
			)
		)
		(property "Footprint" ""
			(at 143.51 52.07 0)
			(effects
				(font
					(size 1.27 1.27)
					(thickness 0.15)
				)
				(justify left bottom)
				(hide yes)
			)
		)
		(property "Datasheet" ""
			(at 143.51 57.15 0)
			(effects
				(font
					(size 1.27 1.27)
					(thickness 0.15)
				)
				(justify left bottom)
				(hide yes)
			)
		)
		(property "Description" ""
			(at 152.4 44.45 0)
			(effects
				(font
					(size 1.27 1.27)
				)
			)
		)
		(property "Author" "Antmicro"
			(at 143.51 52.07 0)
			(effects
				(font
					(size 1.27 1.27)
					(thickness 0.15)
				)
				(justify left bottom)
				(hide yes)
			)
		)
		(property "License" "Apache-2.0"
			(at 143.51 54.61 0)
			(effects
				(font
					(size 1.27 1.27)
					(thickness 0.15)
				)
				(justify left bottom)
				(hide yes)
			)
		)
		(pin "1"
		)
		(instances
			(project "k410t-devboard"
				(path ""
					(reference "#PWR0304")
					(unit 1)
				)
			)
		)
	)
	(symbol
		(lib_id "antmicroResistors0402:R_10R_0402")
		(at 105.41 200.66 0)
		(unit 1)
		(exclude_from_sim no)
		(in_bom yes)
		(on_board yes)
		(dnp no)
		(property "Reference" "R236"
			(at 113.03 199.39 0)
			(effects
				(font
					(size 1.27 1.27)
				)
			)
		)
		(property "Value" "R_10R_0402"
			(at 125.73 213.36 0)
			(effects
				(font
					(size 1.27 1.27)
					(thickness 0.15)
				)
				(justify left bottom)
				(hide yes)
			)
		)
		(property "Footprint" "antmicro-footprints:R_0402_1005Metric"
			(at 125.73 215.9 0)
			(effects
				(font
					(size 1.27 1.27)
					(thickness 0.15)
				)
				(justify left bottom)
				(hide yes)
			)
		)
		(property "Datasheet" "https://www.bourns.com/docs/product-datasheets/cr.pdf"
			(at 125.73 218.44 0)
			(effects
				(font
					(size 1.27 1.27)
					(thickness 0.15)
				)
				(justify left bottom)
				(hide yes)
			)
		)
		(property "Description" ""
			(at 105.41 200.66 0)
			(effects
				(font
					(size 1.27 1.27)
				)
			)
		)
		(property "Manufacturer" "Bourns"
			(at 125.73 223.52 0)
			(effects
				(font
					(size 1.27 1.27)
					(thickness 0.15)
				)
				(justify left bottom)
				(hide yes)
			)
		)
		(property "MPN" "CR0402-FX-10R0GLF"
			(at 125.73 220.98 0)
			(effects
				(font
					(size 1.27 1.27)
					(thickness 0.15)
				)
				(justify left bottom)
				(hide yes)
			)
		)
		(property "Val" "10R"
			(at 103.505 199.39 0)
			(effects
				(font
					(size 1.27 1.27)
					(thickness 0.15)
				)
			)
		)
		(property "License" "Apache-2.0"
			(at 125.73 226.06 0)
			(effects
				(font
					(size 1.27 1.27)
					(thickness 0.15)
				)
				(justify left bottom)
				(hide yes)
			)
		)
		(property "Author" "Antmicro"
			(at 125.73 228.6 0)
			(effects
				(font
					(size 1.27 1.27)
					(thickness 0.15)
				)
				(justify left bottom)
				(hide yes)
			)
		)
		(property "Tolerance" "1%"
			(at 125.73 210.82 0)
			(effects
				(font
					(size 1.27 1.27)
				)
				(justify left bottom)
				(hide yes)
			)
		)
		(pin "1"
		)
		(pin "2"
		)
		(instances
			(project "k410t-devboard"
				(path ""
					(reference "R236")
					(unit 1)
				)
			)
		)
	)
	(symbol
		(lib_id "antmicropower:GND")
		(at 325.12 125.73 0)
		(unit 1)
		(exclude_from_sim no)
		(in_bom yes)
		(on_board yes)
		(dnp no)
		(property "Reference" "#PWR0344"
			(at 325.12 132.08 0)
			(effects
				(font
					(size 1.27 1.27)
				)
				(hide yes)
			)
		)
		(property "Value" "GND"
			(at 325.12 129.54 0)
			(effects
				(font
					(size 1.27 1.27)
				)
			)
		)
		(property "Footprint" ""
			(at 334.01 133.35 0)
			(effects
				(font
					(size 1.27 1.27)
					(thickness 0.15)
				)
				(justify left bottom)
				(hide yes)
			)
		)
		(property "Datasheet" ""
			(at 334.01 138.43 0)
			(effects
				(font
					(size 1.27 1.27)
					(thickness 0.15)
				)
				(justify left bottom)
				(hide yes)
			)
		)
		(property "Description" ""
			(at 325.12 125.73 0)
			(effects
				(font
					(size 1.27 1.27)
				)
			)
		)
		(property "Author" "Antmicro"
			(at 334.01 133.35 0)
			(effects
				(font
					(size 1.27 1.27)
					(thickness 0.15)
				)
				(justify left bottom)
				(hide yes)
			)
		)
		(property "License" "Apache-2.0"
			(at 334.01 135.89 0)
			(effects
				(font
					(size 1.27 1.27)
					(thickness 0.15)
				)
				(justify left bottom)
				(hide yes)
			)
		)
		(pin "1"
		)
		(instances
			(project "k410t-devboard"
				(path ""
					(reference "#PWR0344")
					(unit 1)
				)
			)
		)
	)
	(symbol
		(lib_id "antmicropower:GND")
		(at 280.67 29.21 0)
		(mirror y)
		(unit 1)
		(exclude_from_sim no)
		(in_bom yes)
		(on_board yes)
		(dnp no)
		(fields_autoplaced yes)
		(property "Reference" "#PWR0336"
			(at 280.67 35.56 0)
			(effects
				(font
					(size 1.27 1.27)
				)
				(hide yes)
			)
		)
		(property "Value" "GND"
			(at 280.67 33.02 0)
			(effects
				(font
					(size 1.27 1.27)
				)
			)
		)
		(property "Footprint" ""
			(at 271.78 36.83 0)
			(effects
				(font
					(size 1.27 1.27)
					(thickness 0.15)
				)
				(justify left bottom)
				(hide yes)
			)
		)
		(property "Datasheet" ""
			(at 271.78 41.91 0)
			(effects
				(font
					(size 1.27 1.27)
					(thickness 0.15)
				)
				(justify left bottom)
				(hide yes)
			)
		)
		(property "Description" ""
			(at 280.67 29.21 0)
			(effects
				(font
					(size 1.27 1.27)
				)
			)
		)
		(property "Author" "Antmicro"
			(at 271.78 36.83 0)
			(effects
				(font
					(size 1.27 1.27)
					(thickness 0.15)
				)
				(justify left bottom)
				(hide yes)
			)
		)
		(property "License" "Apache-2.0"
			(at 271.78 39.37 0)
			(effects
				(font
					(size 1.27 1.27)
					(thickness 0.15)
				)
				(justify left bottom)
				(hide yes)
			)
		)
		(pin "1"
		)
		(instances
			(project "k410t-devboard"
				(path ""
					(reference "#PWR0336")
					(unit 1)
				)
			)
		)
	)
	(symbol
		(lib_id "antmicroResistors0603:R_220R_0603")
		(at 262.89 252.73 90)
		(unit 1)
		(exclude_from_sim no)
		(in_bom yes)
		(on_board yes)
		(dnp no)
		(fields_autoplaced yes)
		(property "Reference" "R252"
			(at 265.43 248.9199 90)
			(effects
				(font
					(size 1.27 1.27)
				)
				(justify right)
			)
		)
		(property "Value" "R_220R_0603"
			(at 275.59 232.41 0)
			(effects
				(font
					(size 1.27 1.27)
					(thickness 0.15)
				)
				(justify left bottom)
				(hide yes)
			)
		)
		(property "Footprint" "antmicro-footprints:R_0603_1608Metric"
			(at 278.13 232.41 0)
			(effects
				(font
					(size 1.27 1.27)
					(thickness 0.15)
				)
				(justify left bottom)
				(hide yes)
			)
		)
		(property "Datasheet" "https://www.bourns.com/docs/product-datasheets/cr.pdf"
			(at 280.67 232.41 0)
			(effects
				(font
					(size 1.27 1.27)
					(thickness 0.15)
				)
				(justify left bottom)
				(hide yes)
			)
		)
		(property "Description" ""
			(at 262.89 252.73 0)
			(effects
				(font
					(size 1.27 1.27)
				)
			)
		)
		(property "Manufacturer" "Bourns"
			(at 285.75 232.41 0)
			(effects
				(font
					(size 1.27 1.27)
					(thickness 0.15)
				)
				(justify left bottom)
				(hide yes)
			)
		)
		(property "MPN" "CR0603-FX-2200ELF"
			(at 283.21 232.41 0)
			(effects
				(font
					(size 1.27 1.27)
					(thickness 0.15)
				)
				(justify left bottom)
				(hide yes)
			)
		)
		(property "Val" "220R"
			(at 265.43 251.4599 90)
			(effects
				(font
					(size 1.27 1.27)
					(thickness 0.15)
				)
				(justify right)
			)
		)
		(property "License" "Apache-2.0"
			(at 288.29 232.41 0)
			(effects
				(font
					(size 1.27 1.27)
					(thickness 0.15)
				)
				(justify left bottom)
				(hide yes)
			)
		)
		(property "Author" "Antmicro"
			(at 290.83 232.41 0)
			(effects
				(font
					(size 1.27 1.27)
					(thickness 0.15)
				)
				(justify left bottom)
				(hide yes)
			)
		)
		(property "Tolerance" "1%"
			(at 273.05 232.41 0)
			(effects
				(font
					(size 1.27 1.27)
				)
				(justify left bottom)
				(hide yes)
			)
		)
		(pin "1"
		)
		(pin "2"
		)
		(instances
			(project "k410t-devboard"
				(path ""
					(reference "R252")
					(unit 1)
				)
			)
		)
	)
	(symbol
		(lib_id "antmicroResistors0402:R_10k_0402")
		(at 52.07 236.22 0)
		(mirror x)
		(unit 1)
		(exclude_from_sim no)
		(in_bom no)
		(on_board yes)
		(dnp yes)
		(property "Reference" "R222"
			(at 59.69 234.95 0)
			(effects
				(font
					(size 1.27 1.27)
				)
			)
		)
		(property "Value" "R_10k_0402"
			(at 72.39 223.52 0)
			(effects
				(font
					(size 1.27 1.27)
					(thickness 0.15)
				)
				(justify left bottom)
				(hide yes)
			)
		)
		(property "Footprint" "antmicro-footprints:R_0402_1005Metric"
			(at 72.39 220.98 0)
			(effects
				(font
					(size 1.27 1.27)
					(thickness 0.15)
				)
				(justify left bottom)
				(hide yes)
			)
		)
		(property "Datasheet" "https://www.bourns.com/docs/product-datasheets/cr.pdf"
			(at 72.39 218.44 0)
			(effects
				(font
					(size 1.27 1.27)
					(thickness 0.15)
				)
				(justify left bottom)
				(hide yes)
			)
		)
		(property "Description" ""
			(at 52.07 236.22 0)
			(effects
				(font
					(size 1.27 1.27)
				)
			)
		)
		(property "Manufacturer" "Bourns"
			(at 72.39 213.36 0)
			(effects
				(font
					(size 1.27 1.27)
					(thickness 0.15)
				)
				(justify left bottom)
				(hide yes)
			)
		)
		(property "MPN" "CR0402-FX-1002GLF"
			(at 72.39 215.9 0)
			(effects
				(font
					(size 1.27 1.27)
					(thickness 0.15)
				)
				(justify left bottom)
				(hide yes)
			)
		)
		(property "Val" "10k"
			(at 50.165 234.95 0)
			(effects
				(font
					(size 1.27 1.27)
					(thickness 0.15)
				)
			)
		)
		(property "DNP" "DNP"
			(at 54.61 236.22 0)
			(effects
				(font
					(size 1.27 1.27)
				)
			)
		)
		(property "License" "Apache-2.0"
			(at 72.39 210.82 0)
			(effects
				(font
					(size 1.27 1.27)
					(thickness 0.15)
				)
				(justify left bottom)
				(hide yes)
			)
		)
		(property "Author" "Antmicro"
			(at 72.39 208.28 0)
			(effects
				(font
					(size 1.27 1.27)
					(thickness 0.15)
				)
				(justify left bottom)
				(hide yes)
			)
		)
		(property "Tolerance" "1%"
			(at 72.39 226.06 0)
			(effects
				(font
					(size 1.27 1.27)
				)
				(justify left bottom)
				(hide yes)
			)
		)
		(pin "1"
		)
		(pin "2"
		)
		(instances
			(project "k410t-devboard"
				(path ""
					(reference "R222")
					(unit 1)
				)
			)
		)
	)
	(symbol
		(lib_id "antmicroResistors0402:R_2k2_0402")
		(at 52.07 96.52 0)
		(unit 1)
		(exclude_from_sim no)
		(in_bom yes)
		(on_board yes)
		(dnp no)
		(property "Reference" "R212"
			(at 59.69 95.25 0)
			(effects
				(font
					(size 1.27 1.27)
				)
			)
		)
		(property "Value" "R_2k2_0402"
			(at 72.39 109.22 0)
			(effects
				(font
					(size 1.27 1.27)
					(thickness 0.15)
				)
				(justify left bottom)
				(hide yes)
			)
		)
		(property "Footprint" "antmicro-footprints:R_0402_1005Metric"
			(at 72.39 111.76 0)
			(effects
				(font
					(size 1.27 1.27)
					(thickness 0.15)
				)
				(justify left bottom)
				(hide yes)
			)
		)
		(property "Datasheet" "https://www.bourns.com/docs/product-datasheets/cr.pdf"
			(at 72.39 114.3 0)
			(effects
				(font
					(size 1.27 1.27)
					(thickness 0.15)
				)
				(justify left bottom)
				(hide yes)
			)
		)
		(property "Description" ""
			(at 52.07 96.52 0)
			(effects
				(font
					(size 1.27 1.27)
				)
			)
		)
		(property "Manufacturer" "Bourns"
			(at 72.39 119.38 0)
			(effects
				(font
					(size 1.27 1.27)
					(thickness 0.15)
				)
				(justify left bottom)
				(hide yes)
			)
		)
		(property "MPN" "CR0402-FX-2201GLF"
			(at 72.39 116.84 0)
			(effects
				(font
					(size 1.27 1.27)
					(thickness 0.15)
				)
				(justify left bottom)
				(hide yes)
			)
		)
		(property "Val" "2k2"
			(at 50.165 95.25 0)
			(effects
				(font
					(size 1.27 1.27)
					(thickness 0.15)
				)
			)
		)
		(property "License" "Apache-2.0"
			(at 72.39 121.92 0)
			(effects
				(font
					(size 1.27 1.27)
					(thickness 0.15)
				)
				(justify left bottom)
				(hide yes)
			)
		)
		(property "Author" "Antmicro"
			(at 72.39 124.46 0)
			(effects
				(font
					(size 1.27 1.27)
					(thickness 0.15)
				)
				(justify left bottom)
				(hide yes)
			)
		)
		(property "Tolerance" "1%"
			(at 72.39 106.68 0)
			(effects
				(font
					(size 1.27 1.27)
				)
				(justify left bottom)
				(hide yes)
			)
		)
		(pin "1"
		)
		(pin "2"
		)
		(instances
			(project "k410t-devboard"
				(path ""
					(reference "R212")
					(unit 1)
				)
			)
		)
	)
	(symbol
		(lib_id "antmicropower:GND")
		(at 220.98 163.83 0)
		(unit 1)
		(exclude_from_sim no)
		(in_bom yes)
		(on_board yes)
		(dnp no)
		(property "Reference" "#PWR0315"
			(at 220.98 170.18 0)
			(effects
				(font
					(size 1.27 1.27)
				)
				(hide yes)
			)
		)
		(property "Value" "GND"
			(at 220.98 167.64 0)
			(effects
				(font
					(size 1.27 1.27)
				)
			)
		)
		(property "Footprint" ""
			(at 229.87 171.45 0)
			(effects
				(font
					(size 1.27 1.27)
					(thickness 0.15)
				)
				(justify left bottom)
				(hide yes)
			)
		)
		(property "Datasheet" ""
			(at 229.87 176.53 0)
			(effects
				(font
					(size 1.27 1.27)
					(thickness 0.15)
				)
				(justify left bottom)
				(hide yes)
			)
		)
		(property "Description" ""
			(at 220.98 163.83 0)
			(effects
				(font
					(size 1.27 1.27)
				)
			)
		)
		(property "Author" "Antmicro"
			(at 229.87 171.45 0)
			(effects
				(font
					(size 1.27 1.27)
					(thickness 0.15)
				)
				(justify left bottom)
				(hide yes)
			)
		)
		(property "License" "Apache-2.0"
			(at 229.87 173.99 0)
			(effects
				(font
					(size 1.27 1.27)
					(thickness 0.15)
				)
				(justify left bottom)
				(hide yes)
			)
		)
		(pin "1"
		)
		(instances
			(project "k410t-devboard"
				(path ""
					(reference "#PWR0315")
					(unit 1)
				)
			)
		)
	)
	(symbol
		(lib_id "antmicropower:GND")
		(at 134.62 132.08 0)
		(unit 1)
		(exclude_from_sim no)
		(in_bom yes)
		(on_board yes)
		(dnp no)
		(fields_autoplaced yes)
		(property "Reference" "#PWR0297"
			(at 134.62 138.43 0)
			(effects
				(font
					(size 1.27 1.27)
				)
				(hide yes)
			)
		)
		(property "Value" "GND"
			(at 134.62 135.89 0)
			(effects
				(font
					(size 1.27 1.27)
				)
			)
		)
		(property "Footprint" ""
			(at 143.51 139.7 0)
			(effects
				(font
					(size 1.27 1.27)
					(thickness 0.15)
				)
				(justify left bottom)
				(hide yes)
			)
		)
		(property "Datasheet" ""
			(at 143.51 144.78 0)
			(effects
				(font
					(size 1.27 1.27)
					(thickness 0.15)
				)
				(justify left bottom)
				(hide yes)
			)
		)
		(property "Description" ""
			(at 134.62 132.08 0)
			(effects
				(font
					(size 1.27 1.27)
				)
			)
		)
		(property "Author" "Antmicro"
			(at 143.51 139.7 0)
			(effects
				(font
					(size 1.27 1.27)
					(thickness 0.15)
				)
				(justify left bottom)
				(hide yes)
			)
		)
		(property "License" "Apache-2.0"
			(at 143.51 142.24 0)
			(effects
				(font
					(size 1.27 1.27)
					(thickness 0.15)
				)
				(justify left bottom)
				(hide yes)
			)
		)
		(pin "1"
		)
		(instances
			(project "k410t-devboard"
				(path ""
					(reference "#PWR0297")
					(unit 1)
				)
			)
		)
	)
	(symbol
		(lib_id "antmicropower:+3.3V")
		(at 248.92 152.4 0)
		(unit 1)
		(exclude_from_sim no)
		(in_bom yes)
		(on_board yes)
		(dnp no)
		(fields_autoplaced yes)
		(property "Reference" "#PWR0294"
			(at 248.92 156.21 0)
			(effects
				(font
					(size 1.27 1.27)
				)
				(hide yes)
			)
		)
		(property "Value" "+3V3"
			(at 248.92 148.844 0)
			(effects
				(font
					(size 1.27 1.27)
				)
			)
		)
		(property "Footprint" ""
			(at 248.92 152.4 0)
			(effects
				(font
					(size 1.27 1.27)
				)
				(hide yes)
			)
		)
		(property "Datasheet" ""
			(at 248.92 152.4 0)
			(effects
				(font
					(size 1.27 1.27)
				)
				(hide yes)
			)
		)
		(property "Description" ""
			(at 248.92 152.4 0)
			(effects
				(font
					(size 1.27 1.27)
				)
			)
		)
		(pin "1"
		)
		(instances
			(project "k410t-devboard"
				(path ""
					(reference "#PWR0294")
					(unit 1)
				)
			)
		)
	)
	(symbol
		(lib_id "antmicroResistors0402:R_2k2_0402")
		(at 52.07 254 0)
		(unit 1)
		(exclude_from_sim no)
		(in_bom no)
		(on_board yes)
		(dnp yes)
		(property "Reference" "R226"
			(at 59.69 252.73 0)
			(effects
				(font
					(size 1.27 1.27)
				)
			)
		)
		(property "Value" "R_2k2_0402"
			(at 72.39 266.7 0)
			(effects
				(font
					(size 1.27 1.27)
					(thickness 0.15)
				)
				(justify left bottom)
				(hide yes)
			)
		)
		(property "Footprint" "antmicro-footprints:R_0402_1005Metric"
			(at 72.39 269.24 0)
			(effects
				(font
					(size 1.27 1.27)
					(thickness 0.15)
				)
				(justify left bottom)
				(hide yes)
			)
		)
		(property "Datasheet" "https://www.bourns.com/docs/product-datasheets/cr.pdf"
			(at 72.39 271.78 0)
			(effects
				(font
					(size 1.27 1.27)
					(thickness 0.15)
				)
				(justify left bottom)
				(hide yes)
			)
		)
		(property "Description" ""
			(at 52.07 254 0)
			(effects
				(font
					(size 1.27 1.27)
				)
			)
		)
		(property "Manufacturer" "Bourns"
			(at 72.39 276.86 0)
			(effects
				(font
					(size 1.27 1.27)
					(thickness 0.15)
				)
				(justify left bottom)
				(hide yes)
			)
		)
		(property "MPN" "CR0402-FX-2201GLF"
			(at 72.39 274.32 0)
			(effects
				(font
					(size 1.27 1.27)
					(thickness 0.15)
				)
				(justify left bottom)
				(hide yes)
			)
		)
		(property "Val" "2k2"
			(at 50.165 252.73 0)
			(effects
				(font
					(size 1.27 1.27)
					(thickness 0.15)
				)
			)
		)
		(property "DNP" "DNP"
			(at 54.61 254 0)
			(effects
				(font
					(size 1.27 1.27)
				)
			)
		)
		(property "License" "Apache-2.0"
			(at 72.39 279.4 0)
			(effects
				(font
					(size 1.27 1.27)
					(thickness 0.15)
				)
				(justify left bottom)
				(hide yes)
			)
		)
		(property "Author" "Antmicro"
			(at 72.39 281.94 0)
			(effects
				(font
					(size 1.27 1.27)
					(thickness 0.15)
				)
				(justify left bottom)
				(hide yes)
			)
		)
		(property "Tolerance" "1%"
			(at 72.39 264.16 0)
			(effects
				(font
					(size 1.27 1.27)
				)
				(justify left bottom)
				(hide yes)
			)
		)
		(pin "1"
		)
		(pin "2"
		)
		(instances
			(project "k410t-devboard"
				(path ""
					(reference "R226")
					(unit 1)
				)
			)
		)
	)
	(symbol
		(lib_id "antmicropower:GND")
		(at 68.58 116.84 0)
		(unit 1)
		(exclude_from_sim no)
		(in_bom yes)
		(on_board yes)
		(dnp no)
		(property "Reference" "#PWR0284"
			(at 68.58 123.19 0)
			(effects
				(font
					(size 1.27 1.27)
				)
				(hide yes)
			)
		)
		(property "Value" "GND"
			(at 68.58 120.65 0)
			(effects
				(font
					(size 1.27 1.27)
				)
			)
		)
		(property "Footprint" ""
			(at 77.47 124.46 0)
			(effects
				(font
					(size 1.27 1.27)
					(thickness 0.15)
				)
				(justify left bottom)
				(hide yes)
			)
		)
		(property "Datasheet" ""
			(at 77.47 129.54 0)
			(effects
				(font
					(size 1.27 1.27)
					(thickness 0.15)
				)
				(justify left bottom)
				(hide yes)
			)
		)
		(property "Description" ""
			(at 68.58 116.84 0)
			(effects
				(font
					(size 1.27 1.27)
				)
			)
		)
		(property "Author" "Antmicro"
			(at 77.47 124.46 0)
			(effects
				(font
					(size 1.27 1.27)
					(thickness 0.15)
				)
				(justify left bottom)
				(hide yes)
			)
		)
		(property "License" "Apache-2.0"
			(at 77.47 127 0)
			(effects
				(font
					(size 1.27 1.27)
					(thickness 0.15)
				)
				(justify left bottom)
				(hide yes)
			)
		)
		(pin "1"
		)
		(instances
			(project "k410t-devboard"
				(path ""
					(reference "#PWR0284")
					(unit 1)
				)
			)
		)
	)
	(symbol
		(lib_id "antmicropower:GND")
		(at 269.24 29.21 0)
		(mirror y)
		(unit 1)
		(exclude_from_sim no)
		(in_bom yes)
		(on_board yes)
		(dnp no)
		(fields_autoplaced yes)
		(property "Reference" "#PWR0334"
			(at 269.24 35.56 0)
			(effects
				(font
					(size 1.27 1.27)
				)
				(hide yes)
			)
		)
		(property "Value" "GND"
			(at 269.24 33.02 0)
			(effects
				(font
					(size 1.27 1.27)
				)
			)
		)
		(property "Footprint" ""
			(at 260.35 36.83 0)
			(effects
				(font
					(size 1.27 1.27)
					(thickness 0.15)
				)
				(justify left bottom)
				(hide yes)
			)
		)
		(property "Datasheet" ""
			(at 260.35 41.91 0)
			(effects
				(font
					(size 1.27 1.27)
					(thickness 0.15)
				)
				(justify left bottom)
				(hide yes)
			)
		)
		(property "Description" ""
			(at 269.24 29.21 0)
			(effects
				(font
					(size 1.27 1.27)
				)
			)
		)
		(property "Author" "Antmicro"
			(at 260.35 36.83 0)
			(effects
				(font
					(size 1.27 1.27)
					(thickness 0.15)
				)
				(justify left bottom)
				(hide yes)
			)
		)
		(property "License" "Apache-2.0"
			(at 260.35 39.37 0)
			(effects
				(font
					(size 1.27 1.27)
					(thickness 0.15)
				)
				(justify left bottom)
				(hide yes)
			)
		)
		(pin "1"
		)
		(instances
			(project "k410t-devboard"
				(path ""
					(reference "#PWR0334")
					(unit 1)
				)
			)
		)
	)
	(symbol
		(lib_id "antmicroResistors0402:R_1k_0402")
		(at 25.4 180.34 0)
		(unit 1)
		(exclude_from_sim no)
		(in_bom yes)
		(on_board yes)
		(dnp no)
		(property "Reference" "R198"
			(at 33.02 179.07 0)
			(effects
				(font
					(size 1.27 1.27)
				)
			)
		)
		(property "Value" "R_1k_0402"
			(at 45.72 193.04 0)
			(effects
				(font
					(size 1.27 1.27)
					(thickness 0.15)
				)
				(justify left bottom)
				(hide yes)
			)
		)
		(property "Footprint" "antmicro-footprints:R_0402_1005Metric"
			(at 45.72 195.58 0)
			(effects
				(font
					(size 1.27 1.27)
					(thickness 0.15)
				)
				(justify left bottom)
				(hide yes)
			)
		)
		(property "Datasheet" "https://www.bourns.com/docs/product-datasheets/cr.pdf"
			(at 45.72 198.12 0)
			(effects
				(font
					(size 1.27 1.27)
					(thickness 0.15)
				)
				(justify left bottom)
				(hide yes)
			)
		)
		(property "Description" ""
			(at 25.4 180.34 0)
			(effects
				(font
					(size 1.27 1.27)
				)
			)
		)
		(property "Manufacturer" "Bourns"
			(at 45.72 203.2 0)
			(effects
				(font
					(size 1.27 1.27)
					(thickness 0.15)
				)
				(justify left bottom)
				(hide yes)
			)
		)
		(property "MPN" "CR0402-FX-1001GLF"
			(at 45.72 200.66 0)
			(effects
				(font
					(size 1.27 1.27)
					(thickness 0.15)
				)
				(justify left bottom)
				(hide yes)
			)
		)
		(property "Val" "1k"
			(at 24.13 179.07 0)
			(effects
				(font
					(size 1.27 1.27)
					(thickness 0.15)
				)
			)
		)
		(property "License" "Apache-2.0"
			(at 45.72 205.74 0)
			(effects
				(font
					(size 1.27 1.27)
					(thickness 0.15)
				)
				(justify left bottom)
				(hide yes)
			)
		)
		(property "Author" "Antmicro"
			(at 45.72 208.28 0)
			(effects
				(font
					(size 1.27 1.27)
					(thickness 0.15)
				)
				(justify left bottom)
				(hide yes)
			)
		)
		(property "Tolerance" "1%"
			(at 45.72 190.5 0)
			(effects
				(font
					(size 1.27 1.27)
				)
				(justify left bottom)
				(hide yes)
			)
		)
		(pin "1"
		)
		(pin "2"
		)
		(instances
			(project "k410t-devboard"
				(path ""
					(reference "R198")
					(unit 1)
				)
			)
		)
	)
	(symbol
		(lib_id "antmicroResistors0402:R_0R_0402")
		(at 342.9 173.99 0)
		(unit 1)
		(exclude_from_sim no)
		(in_bom yes)
		(on_board yes)
		(dnp no)
		(property "Reference" "R257"
			(at 350.52 172.72 0)
			(effects
				(font
					(size 1.27 1.27)
				)
			)
		)
		(property "Value" "R_0R_0402"
			(at 363.22 186.69 0)
			(effects
				(font
					(size 1.27 1.27)
					(thickness 0.15)
				)
				(justify left bottom)
				(hide yes)
			)
		)
		(property "Footprint" "antmicro-footprints:R_0402_1005Metric"
			(at 363.22 189.23 0)
			(effects
				(font
					(size 1.27 1.27)
					(thickness 0.15)
				)
				(justify left bottom)
				(hide yes)
			)
		)
		(property "Datasheet" "https://industrial.panasonic.com/cdbs/www-data/pdf/RDA0000/AOA0000C301.pdf"
			(at 363.22 191.77 0)
			(effects
				(font
					(size 1.27 1.27)
					(thickness 0.15)
				)
				(justify left bottom)
				(hide yes)
			)
		)
		(property "Description" ""
			(at 342.9 173.99 0)
			(effects
				(font
					(size 1.27 1.27)
				)
			)
		)
		(property "Manufacturer" "Panasonic"
			(at 363.22 196.85 0)
			(effects
				(font
					(size 1.27 1.27)
					(thickness 0.15)
				)
				(justify left bottom)
				(hide yes)
			)
		)
		(property "MPN" "ERJ2GE0R00X"
			(at 363.22 194.31 0)
			(effects
				(font
					(size 1.27 1.27)
					(thickness 0.15)
				)
				(justify left bottom)
				(hide yes)
			)
		)
		(property "Val" "0R"
			(at 341.63 172.72 0)
			(effects
				(font
					(size 1.27 1.27)
					(thickness 0.15)
				)
			)
		)
		(property "License" "Apache-2.0"
			(at 363.22 199.39 0)
			(effects
				(font
					(size 1.27 1.27)
					(thickness 0.15)
				)
				(justify left bottom)
				(hide yes)
			)
		)
		(property "Author" "Antmicro"
			(at 363.22 201.93 0)
			(effects
				(font
					(size 1.27 1.27)
					(thickness 0.15)
				)
				(justify left bottom)
				(hide yes)
			)
		)
		(property "Tolerance" "~"
			(at 363.22 184.15 0)
			(effects
				(font
					(size 1.27 1.27)
				)
				(justify left bottom)
				(hide yes)
			)
		)
		(property "Current" "1A"
			(at 363.22 204.47 0)
			(effects
				(font
					(size 1.27 1.27)
					(thickness 0.15)
				)
				(justify left bottom)
				(hide yes)
			)
		)
		(pin "1"
		)
		(pin "2"
		)
		(instances
			(project "k410t-devboard"
				(path ""
					(reference "R257")
					(unit 1)
				)
			)
		)
	)
	(symbol
		(lib_id "antmicroResistors0402:R_49R9_0402")
		(at 233.68 186.69 90)
		(unit 1)
		(exclude_from_sim no)
		(in_bom yes)
		(on_board yes)
		(dnp no)
		(fields_autoplaced yes)
		(property "Reference" "R249"
			(at 236.22 182.8799 90)
			(effects
				(font
					(size 1.27 1.27)
				)
				(justify right)
			)
		)
		(property "Value" "R_49R9_0402"
			(at 246.38 166.37 0)
			(effects
				(font
					(size 1.27 1.27)
					(thickness 0.15)
				)
				(justify left bottom)
				(hide yes)
			)
		)
		(property "Footprint" "antmicro-footprints:R_0402_1005Metric"
			(at 248.92 166.37 0)
			(effects
				(font
					(size 1.27 1.27)
					(thickness 0.15)
				)
				(justify left bottom)
				(hide yes)
			)
		)
		(property "Datasheet" "https://www.bourns.com/docs/product-datasheets/cr.pdf"
			(at 251.46 166.37 0)
			(effects
				(font
					(size 1.27 1.27)
					(thickness 0.15)
				)
				(justify left bottom)
				(hide yes)
			)
		)
		(property "Description" ""
			(at 233.68 186.69 0)
			(effects
				(font
					(size 1.27 1.27)
				)
			)
		)
		(property "Manufacturer" "Bourns"
			(at 256.54 166.37 0)
			(effects
				(font
					(size 1.27 1.27)
					(thickness 0.15)
				)
				(justify left bottom)
				(hide yes)
			)
		)
		(property "MPN" "CR0402-FX-49R9GLF"
			(at 254 166.37 0)
			(effects
				(font
					(size 1.27 1.27)
					(thickness 0.15)
				)
				(justify left bottom)
				(hide yes)
			)
		)
		(property "Val" "49R9"
			(at 236.22 185.4199 90)
			(effects
				(font
					(size 1.27 1.27)
					(thickness 0.15)
				)
				(justify right)
			)
		)
		(property "License" "Apache-2.0"
			(at 259.08 166.37 0)
			(effects
				(font
					(size 1.27 1.27)
					(thickness 0.15)
				)
				(justify left bottom)
				(hide yes)
			)
		)
		(property "Author" "Antmicro"
			(at 261.62 166.37 0)
			(effects
				(font
					(size 1.27 1.27)
					(thickness 0.15)
				)
				(justify left bottom)
				(hide yes)
			)
		)
		(property "Tolerance" "1%"
			(at 243.84 166.37 0)
			(effects
				(font
					(size 1.27 1.27)
				)
				(justify left bottom)
				(hide yes)
			)
		)
		(pin "1"
		)
		(pin "2"
		)
		(instances
			(project "k410t-devboard"
				(path ""
					(reference "R249")
					(unit 1)
				)
			)
		)
	)
	(symbol
		(lib_id "antmicropower:GND")
		(at 195.58 163.83 0)
		(mirror y)
		(unit 1)
		(exclude_from_sim no)
		(in_bom yes)
		(on_board yes)
		(dnp no)
		(property "Reference" "#PWR0311"
			(at 195.58 170.18 0)
			(effects
				(font
					(size 1.27 1.27)
				)
				(hide yes)
			)
		)
		(property "Value" "GND"
			(at 195.58 167.64 0)
			(effects
				(font
					(size 1.27 1.27)
				)
			)
		)
		(property "Footprint" ""
			(at 186.69 171.45 0)
			(effects
				(font
					(size 1.27 1.27)
					(thickness 0.15)
				)
				(justify left bottom)
				(hide yes)
			)
		)
		(property "Datasheet" ""
			(at 186.69 176.53 0)
			(effects
				(font
					(size 1.27 1.27)
					(thickness 0.15)
				)
				(justify left bottom)
				(hide yes)
			)
		)
		(property "Description" ""
			(at 195.58 163.83 0)
			(effects
				(font
					(size 1.27 1.27)
				)
			)
		)
		(property "Author" "Antmicro"
			(at 186.69 171.45 0)
			(effects
				(font
					(size 1.27 1.27)
					(thickness 0.15)
				)
				(justify left bottom)
				(hide yes)
			)
		)
		(property "License" "Apache-2.0"
			(at 186.69 173.99 0)
			(effects
				(font
					(size 1.27 1.27)
					(thickness 0.15)
				)
				(justify left bottom)
				(hide yes)
			)
		)
		(pin "1"
		)
		(instances
			(project "k410t-devboard"
				(path ""
					(reference "#PWR0311")
					(unit 1)
				)
			)
		)
	)
	(symbol
		(lib_id "antmicropower:GND")
		(at 250.19 275.59 0)
		(unit 1)
		(exclude_from_sim no)
		(in_bom yes)
		(on_board yes)
		(dnp no)
		(property "Reference" "#PWR0326"
			(at 250.19 281.94 0)
			(effects
				(font
					(size 1.27 1.27)
				)
				(hide yes)
			)
		)
		(property "Value" "GND"
			(at 250.19 279.4 0)
			(effects
				(font
					(size 1.27 1.27)
				)
			)
		)
		(property "Footprint" ""
			(at 259.08 283.21 0)
			(effects
				(font
					(size 1.27 1.27)
					(thickness 0.15)
				)
				(justify left bottom)
				(hide yes)
			)
		)
		(property "Datasheet" ""
			(at 259.08 288.29 0)
			(effects
				(font
					(size 1.27 1.27)
					(thickness 0.15)
				)
				(justify left bottom)
				(hide yes)
			)
		)
		(property "Description" ""
			(at 250.19 275.59 0)
			(effects
				(font
					(size 1.27 1.27)
				)
			)
		)
		(property "Author" "Antmicro"
			(at 259.08 283.21 0)
			(effects
				(font
					(size 1.27 1.27)
					(thickness 0.15)
				)
				(justify left bottom)
				(hide yes)
			)
		)
		(property "License" "Apache-2.0"
			(at 259.08 285.75 0)
			(effects
				(font
					(size 1.27 1.27)
					(thickness 0.15)
				)
				(justify left bottom)
				(hide yes)
			)
		)
		(pin "1"
		)
		(instances
			(project "k410t-devboard"
				(path ""
					(reference "#PWR0326")
					(unit 1)
				)
			)
		)
	)
	(symbol
		(lib_id "antmicroCapacitors0402:C_100n_0402")
		(at 325.12 123.19 90)
		(unit 1)
		(exclude_from_sim no)
		(in_bom yes)
		(on_board yes)
		(dnp no)
		(fields_autoplaced yes)
		(property "Reference" "C291"
			(at 327.66 119.3735 90)
			(effects
				(font
					(size 1.27 1.27)
				)
				(justify right)
			)
		)
		(property "Value" "C_100n_0402"
			(at 335.28 102.87 0)
			(effects
				(font
					(size 1.27 1.27)
					(thickness 0.15)
				)
				(justify left bottom)
				(hide yes)
			)
		)
		(property "Footprint" "antmicro-footprints:C_0402_1005Metric"
			(at 337.82 102.87 0)
			(effects
				(font
					(size 1.27 1.27)
					(thickness 0.15)
				)
				(justify left bottom)
				(hide yes)
			)
		)
		(property "Datasheet" "https://www.murata.com/products/productdetail?partno=GRM155R61H104KE14%23"
			(at 340.36 102.87 0)
			(effects
				(font
					(size 1.27 1.27)
					(thickness 0.15)
				)
				(justify left bottom)
				(hide yes)
			)
		)
		(property "Description" ""
			(at 325.12 123.19 0)
			(effects
				(font
					(size 1.27 1.27)
				)
			)
		)
		(property "Manufacturer" "Murata"
			(at 345.44 102.87 0)
			(effects
				(font
					(size 1.27 1.27)
					(thickness 0.15)
				)
				(justify left bottom)
				(hide yes)
			)
		)
		(property "MPN" "GRM155R61H104KE14D"
			(at 342.9 102.87 0)
			(effects
				(font
					(size 1.27 1.27)
					(thickness 0.15)
				)
				(justify left bottom)
				(hide yes)
			)
		)
		(property "Val" "100n"
			(at 327.66 121.9135 90)
			(effects
				(font
					(size 1.27 1.27)
					(thickness 0.15)
				)
				(justify right)
			)
		)
		(property "License" "Apache-2.0"
			(at 347.98 102.87 0)
			(effects
				(font
					(size 1.27 1.27)
					(thickness 0.15)
				)
				(justify left bottom)
				(hide yes)
			)
		)
		(property "Author" "Antmicro"
			(at 350.52 102.87 0)
			(effects
				(font
					(size 1.27 1.27)
					(thickness 0.15)
				)
				(justify left bottom)
				(hide yes)
			)
		)
		(property "Voltage" "50V"
			(at 353.06 102.87 0)
			(effects
				(font
					(size 1.27 1.27)
				)
				(justify left bottom)
				(hide yes)
			)
		)
		(property "Dielectric" "X5R"
			(at 355.6 102.87 0)
			(effects
				(font
					(size 1.27 1.27)
				)
				(justify left bottom)
				(hide yes)
			)
		)
		(pin "1"
		)
		(pin "2"
		)
		(instances
			(project "k410t-devboard"
				(path ""
					(reference "C291")
					(unit 1)
				)
			)
		)
	)
	(symbol
		(lib_id "antmicroFerriteBeadsandChips:FB_120Z_2A_Murata-BLM18PG_0603")
		(at 232.41 154.94 0)
		(unit 1)
		(exclude_from_sim no)
		(in_bom yes)
		(on_board yes)
		(dnp no)
		(fields_autoplaced yes)
		(property "Reference" "FB8"
			(at 234.9119 148.59 0)
			(effects
				(font
					(size 1.27 1.27)
				)
			)
		)
		(property "Value" "FB_120Z_2A_Murata-BLM18PG_0603"
			(at 234.95 151.765 0)
			(effects
				(font
					(size 1.27 1.27)
					(thickness 0.15)
				)
				(hide yes)
			)
		)
		(property "Footprint" "antmicro-footprints:FB_0603_1608Metric"
			(at 246.38 160.02 0)
			(effects
				(font
					(size 1.27 1.27)
					(thickness 0.15)
				)
				(justify left bottom)
				(hide yes)
			)
		)
		(property "Datasheet" "https://www.murata.com/en-us/products/productdata/8796738650142/ENFA0003.pdf"
			(at 246.38 162.56 0)
			(effects
				(font
					(size 1.27 1.27)
					(thickness 0.15)
				)
				(justify left bottom)
				(hide yes)
			)
		)
		(property "Description" ""
			(at 232.41 154.94 0)
			(effects
				(font
					(size 1.27 1.27)
				)
			)
		)
		(property "MPN" "BLM18PG121SN1D"
			(at 246.38 165.1 0)
			(effects
				(font
					(size 1.27 1.27)
					(thickness 0.15)
				)
				(justify left bottom)
				(hide yes)
			)
		)
		(property "Manufacturer" "Murata"
			(at 246.38 167.64 0)
			(effects
				(font
					(size 1.27 1.27)
					(thickness 0.15)
				)
				(justify left bottom)
				(hide yes)
			)
		)
		(property "Author" "Antmicro"
			(at 246.38 170.18 0)
			(effects
				(font
					(size 1.27 1.27)
					(thickness 0.15)
				)
				(justify left bottom)
				(hide yes)
			)
		)
		(property "License" "Apache-2.0"
			(at 246.38 172.72 0)
			(effects
				(font
					(size 1.27 1.27)
					(thickness 0.15)
				)
				(justify left bottom)
				(hide yes)
			)
		)
		(property "Val" "120Z/2A"
			(at 234.9119 151.13 0)
			(effects
				(font
					(size 1.27 1.27)
				)
			)
		)
		(property "Current" ""
			(at 252.73 177.8 0)
			(effects
				(font
					(size 1.27 1.27)
					(thickness 0.15)
				)
				(justify left bottom)
				(hide yes)
			)
		)
		(pin "1"
		)
		(pin "2"
		)
		(instances
			(project "k410t-devboard"
				(path ""
					(reference "FB8")
					(unit 1)
				)
			)
		)
	)
	(symbol
		(lib_id "antmicroResistors0603:R_220R_0603")
		(at 396.24 97.79 90)
		(unit 1)
		(exclude_from_sim no)
		(in_bom yes)
		(on_board yes)
		(dnp no)
		(fields_autoplaced yes)
		(property "Reference" "R262"
			(at 398.78 93.9799 90)
			(effects
				(font
					(size 1.27 1.27)
				)
				(justify right)
			)
		)
		(property "Value" "R_220R_0603"
			(at 408.94 77.47 0)
			(effects
				(font
					(size 1.27 1.27)
					(thickness 0.15)
				)
				(justify left bottom)
				(hide yes)
			)
		)
		(property "Footprint" "antmicro-footprints:R_0603_1608Metric"
			(at 411.48 77.47 0)
			(effects
				(font
					(size 1.27 1.27)
					(thickness 0.15)
				)
				(justify left bottom)
				(hide yes)
			)
		)
		(property "Datasheet" "https://www.bourns.com/docs/product-datasheets/cr.pdf"
			(at 414.02 77.47 0)
			(effects
				(font
					(size 1.27 1.27)
					(thickness 0.15)
				)
				(justify left bottom)
				(hide yes)
			)
		)
		(property "Description" ""
			(at 396.24 97.79 0)
			(effects
				(font
					(size 1.27 1.27)
				)
			)
		)
		(property "Manufacturer" "Bourns"
			(at 419.1 77.47 0)
			(effects
				(font
					(size 1.27 1.27)
					(thickness 0.15)
				)
				(justify left bottom)
				(hide yes)
			)
		)
		(property "MPN" "CR0603-FX-2200ELF"
			(at 416.56 77.47 0)
			(effects
				(font
					(size 1.27 1.27)
					(thickness 0.15)
				)
				(justify left bottom)
				(hide yes)
			)
		)
		(property "Val" "220R"
			(at 398.78 96.5199 90)
			(effects
				(font
					(size 1.27 1.27)
					(thickness 0.15)
				)
				(justify right)
			)
		)
		(property "License" "Apache-2.0"
			(at 421.64 77.47 0)
			(effects
				(font
					(size 1.27 1.27)
					(thickness 0.15)
				)
				(justify left bottom)
				(hide yes)
			)
		)
		(property "Author" "Antmicro"
			(at 424.18 77.47 0)
			(effects
				(font
					(size 1.27 1.27)
					(thickness 0.15)
				)
				(justify left bottom)
				(hide yes)
			)
		)
		(property "Tolerance" "1%"
			(at 406.4 77.47 0)
			(effects
				(font
					(size 1.27 1.27)
				)
				(justify left bottom)
				(hide yes)
			)
		)
		(pin "1"
		)
		(pin "2"
		)
		(instances
			(project "k410t-devboard"
				(path ""
					(reference "R262")
					(unit 1)
				)
			)
		)
	)
	(symbol
		(lib_id "antmicroResistors0402:R_10R_0402")
		(at 261.62 273.05 90)
		(unit 1)
		(exclude_from_sim no)
		(in_bom yes)
		(on_board yes)
		(dnp no)
		(fields_autoplaced yes)
		(property "Reference" "R246"
			(at 263.525 269.2399 90)
			(effects
				(font
					(size 1.27 1.27)
				)
				(justify right)
			)
		)
		(property "Value" "R_10R_0402"
			(at 274.32 252.73 0)
			(effects
				(font
					(size 1.27 1.27)
					(thickness 0.15)
				)
				(justify left bottom)
				(hide yes)
			)
		)
		(property "Footprint" "antmicro-footprints:R_0402_1005Metric"
			(at 276.86 252.73 0)
			(effects
				(font
					(size 1.27 1.27)
					(thickness 0.15)
				)
				(justify left bottom)
				(hide yes)
			)
		)
		(property "Datasheet" "https://www.bourns.com/docs/product-datasheets/cr.pdf"
			(at 279.4 252.73 0)
			(effects
				(font
					(size 1.27 1.27)
					(thickness 0.15)
				)
				(justify left bottom)
				(hide yes)
			)
		)
		(property "Description" ""
			(at 261.62 273.05 0)
			(effects
				(font
					(size 1.27 1.27)
				)
			)
		)
		(property "Manufacturer" "Bourns"
			(at 284.48 252.73 0)
			(effects
				(font
					(size 1.27 1.27)
					(thickness 0.15)
				)
				(justify left bottom)
				(hide yes)
			)
		)
		(property "MPN" "CR0402-FX-10R0GLF"
			(at 281.94 252.73 0)
			(effects
				(font
					(size 1.27 1.27)
					(thickness 0.15)
				)
				(justify left bottom)
				(hide yes)
			)
		)
		(property "Val" "10R"
			(at 263.525 271.7799 90)
			(effects
				(font
					(size 1.27 1.27)
					(thickness 0.15)
				)
				(justify right)
			)
		)
		(property "License" "Apache-2.0"
			(at 287.02 252.73 0)
			(effects
				(font
					(size 1.27 1.27)
					(thickness 0.15)
				)
				(justify left bottom)
				(hide yes)
			)
		)
		(property "Author" "Antmicro"
			(at 289.56 252.73 0)
			(effects
				(font
					(size 1.27 1.27)
					(thickness 0.15)
				)
				(justify left bottom)
				(hide yes)
			)
		)
		(property "Tolerance" "1%"
			(at 271.78 252.73 0)
			(effects
				(font
					(size 1.27 1.27)
				)
				(justify left bottom)
				(hide yes)
			)
		)
		(pin "1"
		)
		(pin "2"
		)
		(instances
			(project "k410t-devboard"
				(path ""
					(reference "R246")
					(unit 1)
				)
			)
		)
	)
	(symbol
		(lib_id "antmicroResistors0402:R_2k2_0402")
		(at 52.07 102.87 0)
		(unit 1)
		(exclude_from_sim no)
		(in_bom no)
		(on_board yes)
		(dnp yes)
		(property "Reference" "R214"
			(at 59.69 101.6 0)
			(effects
				(font
					(size 1.27 1.27)
				)
			)
		)
		(property "Value" "R_2k2_0402"
			(at 72.39 115.57 0)
			(effects
				(font
					(size 1.27 1.27)
					(thickness 0.15)
				)
				(justify left bottom)
				(hide yes)
			)
		)
		(property "Footprint" "antmicro-footprints:R_0402_1005Metric"
			(at 72.39 118.11 0)
			(effects
				(font
					(size 1.27 1.27)
					(thickness 0.15)
				)
				(justify left bottom)
				(hide yes)
			)
		)
		(property "Datasheet" "https://www.bourns.com/docs/product-datasheets/cr.pdf"
			(at 72.39 120.65 0)
			(effects
				(font
					(size 1.27 1.27)
					(thickness 0.15)
				)
				(justify left bottom)
				(hide yes)
			)
		)
		(property "Description" ""
			(at 52.07 102.87 0)
			(effects
				(font
					(size 1.27 1.27)
				)
			)
		)
		(property "Manufacturer" "Bourns"
			(at 72.39 125.73 0)
			(effects
				(font
					(size 1.27 1.27)
					(thickness 0.15)
				)
				(justify left bottom)
				(hide yes)
			)
		)
		(property "MPN" "CR0402-FX-2201GLF"
			(at 72.39 123.19 0)
			(effects
				(font
					(size 1.27 1.27)
					(thickness 0.15)
				)
				(justify left bottom)
				(hide yes)
			)
		)
		(property "Val" "2k2"
			(at 50.165 101.6 0)
			(effects
				(font
					(size 1.27 1.27)
					(thickness 0.15)
				)
			)
		)
		(property "DNP" "DNP"
			(at 54.61 102.87 0)
			(effects
				(font
					(size 1.27 1.27)
				)
			)
		)
		(property "License" "Apache-2.0"
			(at 72.39 128.27 0)
			(effects
				(font
					(size 1.27 1.27)
					(thickness 0.15)
				)
				(justify left bottom)
				(hide yes)
			)
		)
		(property "Author" "Antmicro"
			(at 72.39 130.81 0)
			(effects
				(font
					(size 1.27 1.27)
					(thickness 0.15)
				)
				(justify left bottom)
				(hide yes)
			)
		)
		(property "Tolerance" "1%"
			(at 72.39 113.03 0)
			(effects
				(font
					(size 1.27 1.27)
				)
				(justify left bottom)
				(hide yes)
			)
		)
		(pin "1"
		)
		(pin "2"
		)
		(instances
			(project "k410t-devboard"
				(path ""
					(reference "R214")
					(unit 1)
				)
			)
		)
	)
	(symbol
		(lib_id "antmicropower:GND")
		(at 130.81 29.21 0)
		(unit 1)
		(exclude_from_sim no)
		(in_bom yes)
		(on_board yes)
		(dnp no)
		(fields_autoplaced yes)
		(property "Reference" "#PWR0295"
			(at 130.81 35.56 0)
			(effects
				(font
					(size 1.27 1.27)
				)
				(hide yes)
			)
		)
		(property "Value" "GND"
			(at 130.81 33.02 0)
			(effects
				(font
					(size 1.27 1.27)
				)
			)
		)
		(property "Footprint" ""
			(at 139.7 36.83 0)
			(effects
				(font
					(size 1.27 1.27)
					(thickness 0.15)
				)
				(justify left bottom)
				(hide yes)
			)
		)
		(property "Datasheet" ""
			(at 139.7 41.91 0)
			(effects
				(font
					(size 1.27 1.27)
					(thickness 0.15)
				)
				(justify left bottom)
				(hide yes)
			)
		)
		(property "Description" ""
			(at 130.81 29.21 0)
			(effects
				(font
					(size 1.27 1.27)
				)
			)
		)
		(property "Author" "Antmicro"
			(at 139.7 36.83 0)
			(effects
				(font
					(size 1.27 1.27)
					(thickness 0.15)
				)
				(justify left bottom)
				(hide yes)
			)
		)
		(property "License" "Apache-2.0"
			(at 139.7 39.37 0)
			(effects
				(font
					(size 1.27 1.27)
					(thickness 0.15)
				)
				(justify left bottom)
				(hide yes)
			)
		)
		(pin "1"
		)
		(instances
			(project "k410t-devboard"
				(path ""
					(reference "#PWR0295")
					(unit 1)
				)
			)
		)
	)
	(symbol
		(lib_id "antmicroResistors0402:R_10R_0402")
		(at 105.41 175.26 0)
		(unit 1)
		(exclude_from_sim no)
		(in_bom yes)
		(on_board yes)
		(dnp no)
		(property "Reference" "R234"
			(at 113.03 173.99 0)
			(effects
				(font
					(size 1.27 1.27)
				)
			)
		)
		(property "Value" "R_10R_0402"
			(at 125.73 187.96 0)
			(effects
				(font
					(size 1.27 1.27)
					(thickness 0.15)
				)
				(justify left bottom)
				(hide yes)
			)
		)
		(property "Footprint" "antmicro-footprints:R_0402_1005Metric"
			(at 125.73 190.5 0)
			(effects
				(font
					(size 1.27 1.27)
					(thickness 0.15)
				)
				(justify left bottom)
				(hide yes)
			)
		)
		(property "Datasheet" "https://www.bourns.com/docs/product-datasheets/cr.pdf"
			(at 125.73 193.04 0)
			(effects
				(font
					(size 1.27 1.27)
					(thickness 0.15)
				)
				(justify left bottom)
				(hide yes)
			)
		)
		(property "Description" ""
			(at 105.41 175.26 0)
			(effects
				(font
					(size 1.27 1.27)
				)
			)
		)
		(property "Manufacturer" "Bourns"
			(at 125.73 198.12 0)
			(effects
				(font
					(size 1.27 1.27)
					(thickness 0.15)
				)
				(justify left bottom)
				(hide yes)
			)
		)
		(property "MPN" "CR0402-FX-10R0GLF"
			(at 125.73 195.58 0)
			(effects
				(font
					(size 1.27 1.27)
					(thickness 0.15)
				)
				(justify left bottom)
				(hide yes)
			)
		)
		(property "Val" "10R"
			(at 103.505 173.99 0)
			(effects
				(font
					(size 1.27 1.27)
					(thickness 0.15)
				)
			)
		)
		(property "License" "Apache-2.0"
			(at 125.73 200.66 0)
			(effects
				(font
					(size 1.27 1.27)
					(thickness 0.15)
				)
				(justify left bottom)
				(hide yes)
			)
		)
		(property "Author" "Antmicro"
			(at 125.73 203.2 0)
			(effects
				(font
					(size 1.27 1.27)
					(thickness 0.15)
				)
				(justify left bottom)
				(hide yes)
			)
		)
		(property "Tolerance" "1%"
			(at 125.73 185.42 0)
			(effects
				(font
					(size 1.27 1.27)
				)
				(justify left bottom)
				(hide yes)
			)
		)
		(pin "1"
		)
		(pin "2"
		)
		(instances
			(project "k410t-devboard"
				(path ""
					(reference "R234")
					(unit 1)
				)
			)
		)
	)
	(symbol
		(lib_id "antmicropower:GND")
		(at 245.11 275.59 0)
		(unit 1)
		(exclude_from_sim no)
		(in_bom yes)
		(on_board yes)
		(dnp no)
		(property "Reference" "#PWR0322"
			(at 245.11 281.94 0)
			(effects
				(font
					(size 1.27 1.27)
				)
				(hide yes)
			)
		)
		(property "Value" "GND"
			(at 245.11 279.4 0)
			(effects
				(font
					(size 1.27 1.27)
				)
			)
		)
		(property "Footprint" ""
			(at 254 283.21 0)
			(effects
				(font
					(size 1.27 1.27)
					(thickness 0.15)
				)
				(justify left bottom)
				(hide yes)
			)
		)
		(property "Datasheet" ""
			(at 254 288.29 0)
			(effects
				(font
					(size 1.27 1.27)
					(thickness 0.15)
				)
				(justify left bottom)
				(hide yes)
			)
		)
		(property "Description" ""
			(at 245.11 275.59 0)
			(effects
				(font
					(size 1.27 1.27)
				)
			)
		)
		(property "Author" "Antmicro"
			(at 254 283.21 0)
			(effects
				(font
					(size 1.27 1.27)
					(thickness 0.15)
				)
				(justify left bottom)
				(hide yes)
			)
		)
		(property "License" "Apache-2.0"
			(at 254 285.75 0)
			(effects
				(font
					(size 1.27 1.27)
					(thickness 0.15)
				)
				(justify left bottom)
				(hide yes)
			)
		)
		(pin "1"
		)
		(instances
			(project "k410t-devboard"
				(path ""
					(reference "#PWR0322")
					(unit 1)
				)
			)
		)
	)
	(symbol
		(lib_id "antmicropower:GND")
		(at 120.65 44.45 0)
		(mirror y)
		(unit 1)
		(exclude_from_sim no)
		(in_bom yes)
		(on_board yes)
		(dnp no)
		(fields_autoplaced yes)
		(property "Reference" "#PWR0290"
			(at 120.65 50.8 0)
			(effects
				(font
					(size 1.27 1.27)
				)
				(hide yes)
			)
		)
		(property "Value" "GND"
			(at 120.65 48.26 0)
			(effects
				(font
					(size 1.27 1.27)
				)
			)
		)
		(property "Footprint" ""
			(at 111.76 52.07 0)
			(effects
				(font
					(size 1.27 1.27)
					(thickness 0.15)
				)
				(justify left bottom)
				(hide yes)
			)
		)
		(property "Datasheet" ""
			(at 111.76 57.15 0)
			(effects
				(font
					(size 1.27 1.27)
					(thickness 0.15)
				)
				(justify left bottom)
				(hide yes)
			)
		)
		(property "Description" ""
			(at 120.65 44.45 0)
			(effects
				(font
					(size 1.27 1.27)
				)
			)
		)
		(property "Author" "Antmicro"
			(at 111.76 52.07 0)
			(effects
				(font
					(size 1.27 1.27)
					(thickness 0.15)
				)
				(justify left bottom)
				(hide yes)
			)
		)
		(property "License" "Apache-2.0"
			(at 111.76 54.61 0)
			(effects
				(font
					(size 1.27 1.27)
					(thickness 0.15)
				)
				(justify left bottom)
				(hide yes)
			)
		)
		(pin "1"
		)
		(instances
			(project "k410t-devboard"
				(path ""
					(reference "#PWR0290")
					(unit 1)
				)
			)
		)
	)
	(symbol
		(lib_id "antmicroResistors0402:R_0R_0402")
		(at 342.9 166.37 0)
		(unit 1)
		(exclude_from_sim no)
		(in_bom yes)
		(on_board yes)
		(dnp no)
		(property "Reference" "R254"
			(at 350.52 165.1 0)
			(effects
				(font
					(size 1.27 1.27)
				)
			)
		)
		(property "Value" "R_0R_0402"
			(at 363.22 179.07 0)
			(effects
				(font
					(size 1.27 1.27)
					(thickness 0.15)
				)
				(justify left bottom)
				(hide yes)
			)
		)
		(property "Footprint" "antmicro-footprints:R_0402_1005Metric"
			(at 363.22 181.61 0)
			(effects
				(font
					(size 1.27 1.27)
					(thickness 0.15)
				)
				(justify left bottom)
				(hide yes)
			)
		)
		(property "Datasheet" "https://industrial.panasonic.com/cdbs/www-data/pdf/RDA0000/AOA0000C301.pdf"
			(at 363.22 184.15 0)
			(effects
				(font
					(size 1.27 1.27)
					(thickness 0.15)
				)
				(justify left bottom)
				(hide yes)
			)
		)
		(property "Description" ""
			(at 342.9 166.37 0)
			(effects
				(font
					(size 1.27 1.27)
				)
			)
		)
		(property "Manufacturer" "Panasonic"
			(at 363.22 189.23 0)
			(effects
				(font
					(size 1.27 1.27)
					(thickness 0.15)
				)
				(justify left bottom)
				(hide yes)
			)
		)
		(property "MPN" "ERJ2GE0R00X"
			(at 363.22 186.69 0)
			(effects
				(font
					(size 1.27 1.27)
					(thickness 0.15)
				)
				(justify left bottom)
				(hide yes)
			)
		)
		(property "Val" "0R"
			(at 341.63 165.1 0)
			(effects
				(font
					(size 1.27 1.27)
					(thickness 0.15)
				)
			)
		)
		(property "License" "Apache-2.0"
			(at 363.22 191.77 0)
			(effects
				(font
					(size 1.27 1.27)
					(thickness 0.15)
				)
				(justify left bottom)
				(hide yes)
			)
		)
		(property "Author" "Antmicro"
			(at 363.22 194.31 0)
			(effects
				(font
					(size 1.27 1.27)
					(thickness 0.15)
				)
				(justify left bottom)
				(hide yes)
			)
		)
		(property "Tolerance" "~"
			(at 363.22 176.53 0)
			(effects
				(font
					(size 1.27 1.27)
				)
				(justify left bottom)
				(hide yes)
			)
		)
		(property "Current" "1A"
			(at 363.22 196.85 0)
			(effects
				(font
					(size 1.27 1.27)
					(thickness 0.15)
				)
				(justify left bottom)
				(hide yes)
			)
		)
		(pin "1"
		)
		(pin "2"
		)
		(instances
			(project "k410t-devboard"
				(path ""
					(reference "R254")
					(unit 1)
				)
			)
		)
	)
	(symbol
		(lib_id "antmicropower:GND")
		(at 261.62 275.59 0)
		(unit 1)
		(exclude_from_sim no)
		(in_bom yes)
		(on_board yes)
		(dnp no)
		(property "Reference" "#PWR0332"
			(at 261.62 281.94 0)
			(effects
				(font
					(size 1.27 1.27)
				)
				(hide yes)
			)
		)
		(property "Value" "GND"
			(at 261.62 279.4 0)
			(effects
				(font
					(size 1.27 1.27)
				)
			)
		)
		(property "Footprint" ""
			(at 270.51 283.21 0)
			(effects
				(font
					(size 1.27 1.27)
					(thickness 0.15)
				)
				(justify left bottom)
				(hide yes)
			)
		)
		(property "Datasheet" ""
			(at 270.51 288.29 0)
			(effects
				(font
					(size 1.27 1.27)
					(thickness 0.15)
				)
				(justify left bottom)
				(hide yes)
			)
		)
		(property "Description" ""
			(at 261.62 275.59 0)
			(effects
				(font
					(size 1.27 1.27)
				)
			)
		)
		(property "Author" "Antmicro"
			(at 270.51 283.21 0)
			(effects
				(font
					(size 1.27 1.27)
					(thickness 0.15)
				)
				(justify left bottom)
				(hide yes)
			)
		)
		(property "License" "Apache-2.0"
			(at 270.51 285.75 0)
			(effects
				(font
					(size 1.27 1.27)
					(thickness 0.15)
				)
				(justify left bottom)
				(hide yes)
			)
		)
		(pin "1"
		)
		(instances
			(project "k410t-devboard"
				(path ""
					(reference "#PWR0332")
					(unit 1)
				)
			)
		)
	)
	(symbol
		(lib_id "antmicropower:GND")
		(at 312.42 168.91 0)
		(unit 1)
		(exclude_from_sim no)
		(in_bom yes)
		(on_board yes)
		(dnp no)
		(property "Reference" "#PWR0339"
			(at 312.42 175.26 0)
			(effects
				(font
					(size 1.27 1.27)
				)
				(hide yes)
			)
		)
		(property "Value" "GND"
			(at 312.42 172.72 0)
			(effects
				(font
					(size 1.27 1.27)
				)
			)
		)
		(property "Footprint" ""
			(at 321.31 176.53 0)
			(effects
				(font
					(size 1.27 1.27)
					(thickness 0.15)
				)
				(justify left bottom)
				(hide yes)
			)
		)
		(property "Datasheet" ""
			(at 321.31 181.61 0)
			(effects
				(font
					(size 1.27 1.27)
					(thickness 0.15)
				)
				(justify left bottom)
				(hide yes)
			)
		)
		(property "Description" ""
			(at 312.42 168.91 0)
			(effects
				(font
					(size 1.27 1.27)
				)
			)
		)
		(property "Author" "Antmicro"
			(at 321.31 176.53 0)
			(effects
				(font
					(size 1.27 1.27)
					(thickness 0.15)
				)
				(justify left bottom)
				(hide yes)
			)
		)
		(property "License" "Apache-2.0"
			(at 321.31 179.07 0)
			(effects
				(font
					(size 1.27 1.27)
					(thickness 0.15)
				)
				(justify left bottom)
				(hide yes)
			)
		)
		(pin "1"
		)
		(instances
			(project "k410t-devboard"
				(path ""
					(reference "#PWR0339")
					(unit 1)
				)
			)
		)
	)
	(symbol
		(lib_id "antmicropower:GND")
		(at 261.62 180.34 0)
		(mirror y)
		(unit 1)
		(exclude_from_sim no)
		(in_bom yes)
		(on_board yes)
		(dnp no)
		(property "Reference" "#PWR0330"
			(at 261.62 186.69 0)
			(effects
				(font
					(size 1.27 1.27)
				)
				(hide yes)
			)
		)
		(property "Value" "GND"
			(at 261.62 184.15 0)
			(effects
				(font
					(size 1.27 1.27)
				)
			)
		)
		(property "Footprint" ""
			(at 252.73 187.96 0)
			(effects
				(font
					(size 1.27 1.27)
					(thickness 0.15)
				)
				(justify left bottom)
				(hide yes)
			)
		)
		(property "Datasheet" ""
			(at 252.73 193.04 0)
			(effects
				(font
					(size 1.27 1.27)
					(thickness 0.15)
				)
				(justify left bottom)
				(hide yes)
			)
		)
		(property "Description" ""
			(at 261.62 180.34 0)
			(effects
				(font
					(size 1.27 1.27)
				)
			)
		)
		(property "Author" "Antmicro"
			(at 252.73 187.96 0)
			(effects
				(font
					(size 1.27 1.27)
					(thickness 0.15)
				)
				(justify left bottom)
				(hide yes)
			)
		)
		(property "License" "Apache-2.0"
			(at 252.73 190.5 0)
			(effects
				(font
					(size 1.27 1.27)
					(thickness 0.15)
				)
				(justify left bottom)
				(hide yes)
			)
		)
		(pin "1"
		)
		(instances
			(project "k410t-devboard"
				(path ""
					(reference "#PWR0330")
					(unit 1)
				)
			)
		)
	)
	(symbol
		(lib_id "antmicroCapacitors0402:C_10u_0402")
		(at 120.65 26.67 90)
		(unit 1)
		(exclude_from_sim no)
		(in_bom yes)
		(on_board yes)
		(dnp no)
		(fields_autoplaced yes)
		(property "Reference" "C254"
			(at 123.825 22.8535 90)
			(effects
				(font
					(size 1.27 1.27)
				)
				(justify right)
			)
		)
		(property "Value" "C_10u_0402"
			(at 130.81 6.35 0)
			(effects
				(font
					(size 1.27 1.27)
					(thickness 0.15)
				)
				(justify left bottom)
				(hide yes)
			)
		)
		(property "Footprint" "antmicro-footprints:C_0402_1005Metric"
			(at 133.35 6.35 0)
			(effects
				(font
					(size 1.27 1.27)
					(thickness 0.15)
				)
				(justify left bottom)
				(hide yes)
			)
		)
		(property "Datasheet" "https://www.yageo.com/en/Chart/Download/pdf/CC0402MRX5R5BB106"
			(at 135.89 6.35 0)
			(effects
				(font
					(size 1.27 1.27)
					(thickness 0.15)
				)
				(justify left bottom)
				(hide yes)
			)
		)
		(property "Description" ""
			(at 120.65 26.67 0)
			(effects
				(font
					(size 1.27 1.27)
				)
			)
		)
		(property "Manufacturer" "YAGEO"
			(at 140.97 6.35 0)
			(effects
				(font
					(size 1.27 1.27)
					(thickness 0.15)
				)
				(justify left bottom)
				(hide yes)
			)
		)
		(property "MPN" "CC0402MRX5R5BB106"
			(at 138.43 6.35 0)
			(effects
				(font
					(size 1.27 1.27)
					(thickness 0.15)
				)
				(justify left bottom)
				(hide yes)
			)
		)
		(property "Val" "10u"
			(at 123.825 25.3935 90)
			(effects
				(font
					(size 1.27 1.27)
					(thickness 0.15)
				)
				(justify right)
			)
		)
		(property "License" "Apache-2.0"
			(at 143.51 6.35 0)
			(effects
				(font
					(size 1.27 1.27)
					(thickness 0.15)
				)
				(justify left bottom)
				(hide yes)
			)
		)
		(property "Author" "Antmicro"
			(at 146.05 6.35 0)
			(effects
				(font
					(size 1.27 1.27)
					(thickness 0.15)
				)
				(justify left bottom)
				(hide yes)
			)
		)
		(property "Voltage" ""
			(at 148.59 6.35 0)
			(effects
				(font
					(size 1.27 1.27)
				)
				(justify left bottom)
				(hide yes)
			)
		)
		(property "Dielectric" ""
			(at 151.13 6.35 0)
			(effects
				(font
					(size 1.27 1.27)
				)
				(justify left bottom)
				(hide yes)
			)
		)
		(pin "1"
		)
		(pin "2"
		)
		(instances
			(project "k410t-devboard"
				(path ""
					(reference "C254")
					(unit 1)
				)
			)
		)
	)
	(symbol
		(lib_id "antmicroResistors0402:R_10k_0402")
		(at 52.07 243.84 0)
		(mirror x)
		(unit 1)
		(exclude_from_sim no)
		(in_bom no)
		(on_board yes)
		(dnp yes)
		(property "Reference" "R224"
			(at 59.69 242.57 0)
			(effects
				(font
					(size 1.27 1.27)
				)
			)
		)
		(property "Value" "R_10k_0402"
			(at 72.39 231.14 0)
			(effects
				(font
					(size 1.27 1.27)
					(thickness 0.15)
				)
				(justify left bottom)
				(hide yes)
			)
		)
		(property "Footprint" "antmicro-footprints:R_0402_1005Metric"
			(at 72.39 228.6 0)
			(effects
				(font
					(size 1.27 1.27)
					(thickness 0.15)
				)
				(justify left bottom)
				(hide yes)
			)
		)
		(property "Datasheet" "https://www.bourns.com/docs/product-datasheets/cr.pdf"
			(at 72.39 226.06 0)
			(effects
				(font
					(size 1.27 1.27)
					(thickness 0.15)
				)
				(justify left bottom)
				(hide yes)
			)
		)
		(property "Description" ""
			(at 52.07 243.84 0)
			(effects
				(font
					(size 1.27 1.27)
				)
			)
		)
		(property "Manufacturer" "Bourns"
			(at 72.39 220.98 0)
			(effects
				(font
					(size 1.27 1.27)
					(thickness 0.15)
				)
				(justify left bottom)
				(hide yes)
			)
		)
		(property "MPN" "CR0402-FX-1002GLF"
			(at 72.39 223.52 0)
			(effects
				(font
					(size 1.27 1.27)
					(thickness 0.15)
				)
				(justify left bottom)
				(hide yes)
			)
		)
		(property "Val" "10k"
			(at 50.165 242.57 0)
			(effects
				(font
					(size 1.27 1.27)
					(thickness 0.15)
				)
			)
		)
		(property "DNP" "DNP"
			(at 54.61 243.84 0)
			(effects
				(font
					(size 1.27 1.27)
				)
			)
		)
		(property "License" "Apache-2.0"
			(at 72.39 218.44 0)
			(effects
				(font
					(size 1.27 1.27)
					(thickness 0.15)
				)
				(justify left bottom)
				(hide yes)
			)
		)
		(property "Author" "Antmicro"
			(at 72.39 215.9 0)
			(effects
				(font
					(size 1.27 1.27)
					(thickness 0.15)
				)
				(justify left bottom)
				(hide yes)
			)
		)
		(property "Tolerance" "1%"
			(at 72.39 233.68 0)
			(effects
				(font
					(size 1.27 1.27)
				)
				(justify left bottom)
				(hide yes)
			)
		)
		(pin "1"
		)
		(pin "2"
		)
		(instances
			(project "k410t-devboard"
				(path ""
					(reference "R224")
					(unit 1)
				)
			)
		)
	)
	(symbol
		(lib_id "antmicroCapacitors0402:C_100n_0402")
		(at 290.83 26.67 90)
		(unit 1)
		(exclude_from_sim no)
		(in_bom yes)
		(on_board yes)
		(dnp no)
		(property "Reference" "C290"
			(at 291.465 22.225 90)
			(effects
				(font
					(size 1.27 1.27)
				)
				(justify right)
			)
		)
		(property "Value" "C_100n_0402"
			(at 300.99 6.35 0)
			(effects
				(font
					(size 1.27 1.27)
					(thickness 0.15)
				)
				(justify left bottom)
				(hide yes)
			)
		)
		(property "Footprint" "antmicro-footprints:C_0402_1005Metric"
			(at 303.53 6.35 0)
			(effects
				(font
					(size 1.27 1.27)
					(thickness 0.15)
				)
				(justify left bottom)
				(hide yes)
			)
		)
		(property "Datasheet" "https://www.murata.com/products/productdetail?partno=GRM155R61H104KE14%23"
			(at 306.07 6.35 0)
			(effects
				(font
					(size 1.27 1.27)
					(thickness 0.15)
				)
				(justify left bottom)
				(hide yes)
			)
		)
		(property "Description" ""
			(at 290.83 26.67 0)
			(effects
				(font
					(size 1.27 1.27)
				)
			)
		)
		(property "Manufacturer" "Murata"
			(at 311.15 6.35 0)
			(effects
				(font
					(size 1.27 1.27)
					(thickness 0.15)
				)
				(justify left bottom)
				(hide yes)
			)
		)
		(property "MPN" "GRM155R61H104KE14D"
			(at 308.61 6.35 0)
			(effects
				(font
					(size 1.27 1.27)
					(thickness 0.15)
				)
				(justify left bottom)
				(hide yes)
			)
		)
		(property "Val" "100n"
			(at 291.465 26.035 90)
			(effects
				(font
					(size 1.27 1.27)
					(thickness 0.15)
				)
				(justify right)
			)
		)
		(property "License" "Apache-2.0"
			(at 313.69 6.35 0)
			(effects
				(font
					(size 1.27 1.27)
					(thickness 0.15)
				)
				(justify left bottom)
				(hide yes)
			)
		)
		(property "Author" "Antmicro"
			(at 316.23 6.35 0)
			(effects
				(font
					(size 1.27 1.27)
					(thickness 0.15)
				)
				(justify left bottom)
				(hide yes)
			)
		)
		(property "Voltage" "50V"
			(at 318.77 6.35 0)
			(effects
				(font
					(size 1.27 1.27)
				)
				(justify left bottom)
				(hide yes)
			)
		)
		(property "Dielectric" "X5R"
			(at 321.31 6.35 0)
			(effects
				(font
					(size 1.27 1.27)
				)
				(justify left bottom)
				(hide yes)
			)
		)
		(pin "1"
		)
		(pin "2"
		)
		(instances
			(project "k410t-devboard"
				(path ""
					(reference "C290")
					(unit 1)
				)
			)
		)
	)
	(symbol
		(lib_id "antmicroResistors0402:R_10k_0402")
		(at 52.07 55.88 0)
		(mirror x)
		(unit 1)
		(exclude_from_sim no)
		(in_bom yes)
		(on_board yes)
		(dnp no)
		(property "Reference" "R199"
			(at 59.69 54.61 0)
			(effects
				(font
					(size 1.27 1.27)
				)
			)
		)
		(property "Value" "R_10k_0402"
			(at 72.39 43.18 0)
			(effects
				(font
					(size 1.27 1.27)
					(thickness 0.15)
				)
				(justify left bottom)
				(hide yes)
			)
		)
		(property "Footprint" "antmicro-footprints:R_0402_1005Metric"
			(at 72.39 40.64 0)
			(effects
				(font
					(size 1.27 1.27)
					(thickness 0.15)
				)
				(justify left bottom)
				(hide yes)
			)
		)
		(property "Datasheet" "https://www.bourns.com/docs/product-datasheets/cr.pdf"
			(at 72.39 38.1 0)
			(effects
				(font
					(size 1.27 1.27)
					(thickness 0.15)
				)
				(justify left bottom)
				(hide yes)
			)
		)
		(property "Description" ""
			(at 52.07 55.88 0)
			(effects
				(font
					(size 1.27 1.27)
				)
			)
		)
		(property "Manufacturer" "Bourns"
			(at 72.39 33.02 0)
			(effects
				(font
					(size 1.27 1.27)
					(thickness 0.15)
				)
				(justify left bottom)
				(hide yes)
			)
		)
		(property "MPN" "CR0402-FX-1002GLF"
			(at 72.39 35.56 0)
			(effects
				(font
					(size 1.27 1.27)
					(thickness 0.15)
				)
				(justify left bottom)
				(hide yes)
			)
		)
		(property "Val" "10k"
			(at 50.165 54.61 0)
			(effects
				(font
					(size 1.27 1.27)
					(thickness 0.15)
				)
			)
		)
		(property "License" "Apache-2.0"
			(at 72.39 30.48 0)
			(effects
				(font
					(size 1.27 1.27)
					(thickness 0.15)
				)
				(justify left bottom)
				(hide yes)
			)
		)
		(property "Author" "Antmicro"
			(at 72.39 27.94 0)
			(effects
				(font
					(size 1.27 1.27)
					(thickness 0.15)
				)
				(justify left bottom)
				(hide yes)
			)
		)
		(property "Tolerance" "1%"
			(at 72.39 45.72 0)
			(effects
				(font
					(size 1.27 1.27)
				)
				(justify left bottom)
				(hide yes)
			)
		)
		(pin "1"
		)
		(pin "2"
		)
		(instances
			(project "k410t-devboard"
				(path ""
					(reference "R199")
					(unit 1)
				)
			)
		)
	)
	(symbol
		(lib_id "antmicroResistors0402:R_10R_0402")
		(at 81.28 187.96 0)
		(unit 1)
		(exclude_from_sim no)
		(in_bom yes)
		(on_board yes)
		(dnp no)
		(property "Reference" "R231"
			(at 88.9 186.69 0)
			(effects
				(font
					(size 1.27 1.27)
				)
			)
		)
		(property "Value" "R_10R_0402"
			(at 101.6 200.66 0)
			(effects
				(font
					(size 1.27 1.27)
					(thickness 0.15)
				)
				(justify left bottom)
				(hide yes)
			)
		)
		(property "Footprint" "antmicro-footprints:R_0402_1005Metric"
			(at 101.6 203.2 0)
			(effects
				(font
					(size 1.27 1.27)
					(thickness 0.15)
				)
				(justify left bottom)
				(hide yes)
			)
		)
		(property "Datasheet" "https://www.bourns.com/docs/product-datasheets/cr.pdf"
			(at 101.6 205.74 0)
			(effects
				(font
					(size 1.27 1.27)
					(thickness 0.15)
				)
				(justify left bottom)
				(hide yes)
			)
		)
		(property "Description" ""
			(at 81.28 187.96 0)
			(effects
				(font
					(size 1.27 1.27)
				)
			)
		)
		(property "Manufacturer" "Bourns"
			(at 101.6 210.82 0)
			(effects
				(font
					(size 1.27 1.27)
					(thickness 0.15)
				)
				(justify left bottom)
				(hide yes)
			)
		)
		(property "MPN" "CR0402-FX-10R0GLF"
			(at 101.6 208.28 0)
			(effects
				(font
					(size 1.27 1.27)
					(thickness 0.15)
				)
				(justify left bottom)
				(hide yes)
			)
		)
		(property "Val" "10R"
			(at 79.375 186.69 0)
			(effects
				(font
					(size 1.27 1.27)
					(thickness 0.15)
				)
			)
		)
		(property "License" "Apache-2.0"
			(at 101.6 213.36 0)
			(effects
				(font
					(size 1.27 1.27)
					(thickness 0.15)
				)
				(justify left bottom)
				(hide yes)
			)
		)
		(property "Author" "Antmicro"
			(at 101.6 215.9 0)
			(effects
				(font
					(size 1.27 1.27)
					(thickness 0.15)
				)
				(justify left bottom)
				(hide yes)
			)
		)
		(property "Tolerance" "1%"
			(at 101.6 198.12 0)
			(effects
				(font
					(size 1.27 1.27)
				)
				(justify left bottom)
				(hide yes)
			)
		)
		(pin "1"
		)
		(pin "2"
		)
		(instances
			(project "k410t-devboard"
				(path ""
					(reference "R231")
					(unit 1)
				)
			)
		)
	)
	(symbol
		(lib_id "antmicroCapacitors0402:C_100n_0402")
		(at 184.15 162.56 90)
		(unit 1)
		(exclude_from_sim no)
		(in_bom yes)
		(on_board yes)
		(dnp no)
		(property "Reference" "C267"
			(at 184.785 158.115 90)
			(effects
				(font
					(size 1.27 1.27)
				)
				(justify right)
			)
		)
		(property "Value" "C_100n_0402"
			(at 194.31 142.24 0)
			(effects
				(font
					(size 1.27 1.27)
					(thickness 0.15)
				)
				(justify left bottom)
				(hide yes)
			)
		)
		(property "Footprint" "antmicro-footprints:C_0402_1005Metric"
			(at 196.85 142.24 0)
			(effects
				(font
					(size 1.27 1.27)
					(thickness 0.15)
				)
				(justify left bottom)
				(hide yes)
			)
		)
		(property "Datasheet" "https://www.murata.com/products/productdetail?partno=GRM155R61H104KE14%23"
			(at 199.39 142.24 0)
			(effects
				(font
					(size 1.27 1.27)
					(thickness 0.15)
				)
				(justify left bottom)
				(hide yes)
			)
		)
		(property "Description" ""
			(at 184.15 162.56 0)
			(effects
				(font
					(size 1.27 1.27)
				)
			)
		)
		(property "Manufacturer" "Murata"
			(at 204.47 142.24 0)
			(effects
				(font
					(size 1.27 1.27)
					(thickness 0.15)
				)
				(justify left bottom)
				(hide yes)
			)
		)
		(property "MPN" "GRM155R61H104KE14D"
			(at 201.93 142.24 0)
			(effects
				(font
					(size 1.27 1.27)
					(thickness 0.15)
				)
				(justify left bottom)
				(hide yes)
			)
		)
		(property "Val" "100n"
			(at 184.785 161.925 90)
			(effects
				(font
					(size 1.27 1.27)
					(thickness 0.15)
				)
				(justify right)
			)
		)
		(property "License" "Apache-2.0"
			(at 207.01 142.24 0)
			(effects
				(font
					(size 1.27 1.27)
					(thickness 0.15)
				)
				(justify left bottom)
				(hide yes)
			)
		)
		(property "Author" "Antmicro"
			(at 209.55 142.24 0)
			(effects
				(font
					(size 1.27 1.27)
					(thickness 0.15)
				)
				(justify left bottom)
				(hide yes)
			)
		)
		(property "Voltage" "50V"
			(at 212.09 142.24 0)
			(effects
				(font
					(size 1.27 1.27)
				)
				(justify left bottom)
				(hide yes)
			)
		)
		(property "Dielectric" "X5R"
			(at 214.63 142.24 0)
			(effects
				(font
					(size 1.27 1.27)
				)
				(justify left bottom)
				(hide yes)
			)
		)
		(pin "1"
		)
		(pin "2"
		)
		(instances
			(project "k410t-devboard"
				(path ""
					(reference "C267")
					(unit 1)
				)
			)
		)
	)
	(symbol
		(lib_id "antmicroVideoConnectors:HDMI-A_TE_2007435-1")
		(at 379.73 166.37 0)
		(unit 1)
		(exclude_from_sim no)
		(in_bom yes)
		(on_board yes)
		(dnp no)
		(fields_autoplaced yes)
		(property "Reference" "J16"
			(at 392.43 158.75 0)
			(effects
				(font
					(size 1.27 1.27)
					(thickness 0.15)
				)
			)
		)
		(property "Value" "HDMI-A_TE_2007435-1"
			(at 392.43 161.29 0)
			(effects
				(font
					(size 1.27 1.27)
					(thickness 0.15)
				)
				(hide yes)
			)
		)
		(property "Footprint" "antmicro-footprints:HDMI-A_Receptacle_TE_2007435-1"
			(at 415.29 173.99 0)
			(effects
				(font
					(size 1.27 1.27)
					(thickness 0.15)
				)
				(justify left bottom)
				(hide yes)
			)
		)
		(property "Datasheet" "https://www.te.com/usa-en/product-2007435-1.html"
			(at 415.29 176.53 0)
			(effects
				(font
					(size 1.27 1.27)
					(thickness 0.15)
				)
				(justify left bottom)
				(hide yes)
			)
		)
		(property "Description" ""
			(at 379.73 166.37 0)
			(effects
				(font
					(size 1.27 1.27)
				)
			)
		)
		(property "MPN" "2007435-1"
			(at 392.43 161.29 0)
			(effects
				(font
					(size 1.27 1.27)
					(thickness 0.15)
				)
			)
		)
		(property "Manufacturer" "TE Connectivity"
			(at 415.29 181.61 0)
			(effects
				(font
					(size 1.27 1.27)
					(thickness 0.15)
				)
				(justify left bottom)
				(hide yes)
			)
		)
		(property "Author" "Antmicro"
			(at 415.29 184.15 0)
			(effects
				(font
					(size 1.27 1.27)
					(thickness 0.15)
				)
				(justify left bottom)
				(hide yes)
			)
		)
		(property "License" "Apache-2.0"
			(at 415.29 186.69 0)
			(effects
				(font
					(size 1.27 1.27)
					(thickness 0.15)
				)
				(justify left bottom)
				(hide yes)
			)
		)
		(pin "13"
		)
		(pin "6"
		)
		(pin "15"
		)
		(pin "16"
		)
		(pin "5"
		)
		(pin "14"
		)
		(pin "8"
		)
		(pin "17"
		)
		(pin "9"
		)
		(pin "7"
		)
		(pin "18"
		)
		(pin "19"
		)
		(pin "SH"
		)
		(pin "2"
		)
		(pin "11"
		)
		(pin "3"
		)
		(pin "1"
		)
		(pin "12"
		)
		(pin "4"
		)
		(pin "10"
		)
		(instances
			(project "k410t-devboard"
				(path ""
					(reference "J16")
					(unit 1)
				)
			)
		)
	)
	(symbol
		(lib_id "antmicroResistors0402:R_2k2_0402")
		(at 52.07 91.44 0)
		(unit 1)
		(exclude_from_sim no)
		(in_bom no)
		(on_board yes)
		(dnp yes)
		(property "Reference" "R210"
			(at 59.69 90.17 0)
			(effects
				(font
					(size 1.27 1.27)
				)
			)
		)
		(property "Value" "R_2k2_0402"
			(at 72.39 104.14 0)
			(effects
				(font
					(size 1.27 1.27)
					(thickness 0.15)
				)
				(justify left bottom)
				(hide yes)
			)
		)
		(property "Footprint" "antmicro-footprints:R_0402_1005Metric"
			(at 72.39 106.68 0)
			(effects
				(font
					(size 1.27 1.27)
					(thickness 0.15)
				)
				(justify left bottom)
				(hide yes)
			)
		)
		(property "Datasheet" "https://www.bourns.com/docs/product-datasheets/cr.pdf"
			(at 72.39 109.22 0)
			(effects
				(font
					(size 1.27 1.27)
					(thickness 0.15)
				)
				(justify left bottom)
				(hide yes)
			)
		)
		(property "Description" ""
			(at 52.07 91.44 0)
			(effects
				(font
					(size 1.27 1.27)
				)
			)
		)
		(property "Manufacturer" "Bourns"
			(at 72.39 114.3 0)
			(effects
				(font
					(size 1.27 1.27)
					(thickness 0.15)
				)
				(justify left bottom)
				(hide yes)
			)
		)
		(property "MPN" "CR0402-FX-2201GLF"
			(at 72.39 111.76 0)
			(effects
				(font
					(size 1.27 1.27)
					(thickness 0.15)
				)
				(justify left bottom)
				(hide yes)
			)
		)
		(property "Val" "2k2"
			(at 50.165 90.17 0)
			(effects
				(font
					(size 1.27 1.27)
					(thickness 0.15)
				)
			)
		)
		(property "DNP" "DNP"
			(at 54.61 91.44 0)
			(effects
				(font
					(size 1.27 1.27)
				)
			)
		)
		(property "License" "Apache-2.0"
			(at 72.39 116.84 0)
			(effects
				(font
					(size 1.27 1.27)
					(thickness 0.15)
				)
				(justify left bottom)
				(hide yes)
			)
		)
		(property "Author" "Antmicro"
			(at 72.39 119.38 0)
			(effects
				(font
					(size 1.27 1.27)
					(thickness 0.15)
				)
				(justify left bottom)
				(hide yes)
			)
		)
		(property "Tolerance" "1%"
			(at 72.39 101.6 0)
			(effects
				(font
					(size 1.27 1.27)
				)
				(justify left bottom)
				(hide yes)
			)
		)
		(pin "1"
		)
		(pin "2"
		)
		(instances
			(project "k410t-devboard"
				(path ""
					(reference "R210")
					(unit 1)
				)
			)
		)
	)
	(symbol
		(lib_id "antmicropower:GND")
		(at 152.4 29.21 0)
		(unit 1)
		(exclude_from_sim no)
		(in_bom yes)
		(on_board yes)
		(dnp no)
		(fields_autoplaced yes)
		(property "Reference" "#PWR0303"
			(at 152.4 35.56 0)
			(effects
				(font
					(size 1.27 1.27)
				)
				(hide yes)
			)
		)
		(property "Value" "GND"
			(at 152.4 33.02 0)
			(effects
				(font
					(size 1.27 1.27)
				)
			)
		)
		(property "Footprint" ""
			(at 161.29 36.83 0)
			(effects
				(font
					(size 1.27 1.27)
					(thickness 0.15)
				)
				(justify left bottom)
				(hide yes)
			)
		)
		(property "Datasheet" ""
			(at 161.29 41.91 0)
			(effects
				(font
					(size 1.27 1.27)
					(thickness 0.15)
				)
				(justify left bottom)
				(hide yes)
			)
		)
		(property "Description" ""
			(at 152.4 29.21 0)
			(effects
				(font
					(size 1.27 1.27)
				)
			)
		)
		(property "Author" "Antmicro"
			(at 161.29 36.83 0)
			(effects
				(font
					(size 1.27 1.27)
					(thickness 0.15)
				)
				(justify left bottom)
				(hide yes)
			)
		)
		(property "License" "Apache-2.0"
			(at 161.29 39.37 0)
			(effects
				(font
					(size 1.27 1.27)
					(thickness 0.15)
				)
				(justify left bottom)
				(hide yes)
			)
		)
		(pin "1"
		)
		(instances
			(project "k410t-devboard"
				(path ""
					(reference "#PWR0303")
					(unit 1)
				)
			)
		)
	)
	(symbol
		(lib_id "antmicroResistors0402:R_1M_0402")
		(at 121.92 220.98 180)
		(unit 1)
		(exclude_from_sim no)
		(in_bom yes)
		(on_board yes)
		(dnp no)
		(property "Reference" "R241"
			(at 124.46 219.71 0)
			(effects
				(font
					(size 1.27 1.27)
				)
			)
		)
		(property "Value" "R_1M_0402"
			(at 101.6 208.28 0)
			(effects
				(font
					(size 1.27 1.27)
					(thickness 0.15)
				)
				(justify left bottom)
				(hide yes)
			)
		)
		(property "Footprint" "antmicro-footprints:R_0402_1005Metric"
			(at 101.6 205.74 0)
			(effects
				(font
					(size 1.27 1.27)
					(thickness 0.15)
				)
				(justify left bottom)
				(hide yes)
			)
		)
		(property "Datasheet" "https://www.bourns.com/docs/product-datasheets/cr.pdf"
			(at 101.6 203.2 0)
			(effects
				(font
					(size 1.27 1.27)
					(thickness 0.15)
				)
				(justify left bottom)
				(hide yes)
			)
		)
		(property "Description" ""
			(at 121.92 220.98 0)
			(effects
				(font
					(size 1.27 1.27)
				)
			)
		)
		(property "Manufacturer" "Bourns"
			(at 101.6 198.12 0)
			(effects
				(font
					(size 1.27 1.27)
					(thickness 0.15)
				)
				(justify left bottom)
				(hide yes)
			)
		)
		(property "MPN" "CR0402-FX-1004GLF"
			(at 101.6 200.66 0)
			(effects
				(font
					(size 1.27 1.27)
					(thickness 0.15)
				)
				(justify left bottom)
				(hide yes)
			)
		)
		(property "Val" "1M"
			(at 115.57 219.71 0)
			(effects
				(font
					(size 1.27 1.27)
					(thickness 0.15)
				)
			)
		)
		(property "License" "Apache-2.0"
			(at 101.6 195.58 0)
			(effects
				(font
					(size 1.27 1.27)
					(thickness 0.15)
				)
				(justify left bottom)
				(hide yes)
			)
		)
		(property "Author" "Antmicro"
			(at 101.6 193.04 0)
			(effects
				(font
					(size 1.27 1.27)
					(thickness 0.15)
				)
				(justify left bottom)
				(hide yes)
			)
		)
		(property "Tolerance" "1%"
			(at 101.6 210.82 0)
			(effects
				(font
					(size 1.27 1.27)
				)
				(justify left bottom)
				(hide yes)
			)
		)
		(pin "1"
		)
		(pin "2"
		)
		(instances
			(project "k410t-devboard"
				(path ""
					(reference "R241")
					(unit 1)
				)
			)
		)
	)
	(symbol
		(lib_id "antmicropower:GND")
		(at 184.15 182.88 0)
		(mirror y)
		(unit 1)
		(exclude_from_sim no)
		(in_bom yes)
		(on_board yes)
		(dnp no)
		(property "Reference" "#PWR0308"
			(at 184.15 189.23 0)
			(effects
				(font
					(size 1.27 1.27)
				)
				(hide yes)
			)
		)
		(property "Value" "GND"
			(at 184.15 186.69 0)
			(effects
				(font
					(size 1.27 1.27)
				)
			)
		)
		(property "Footprint" ""
			(at 175.26 190.5 0)
			(effects
				(font
					(size 1.27 1.27)
					(thickness 0.15)
				)
				(justify left bottom)
				(hide yes)
			)
		)
		(property "Datasheet" ""
			(at 175.26 195.58 0)
			(effects
				(font
					(size 1.27 1.27)
					(thickness 0.15)
				)
				(justify left bottom)
				(hide yes)
			)
		)
		(property "Description" ""
			(at 184.15 182.88 0)
			(effects
				(font
					(size 1.27 1.27)
				)
			)
		)
		(property "Author" "Antmicro"
			(at 175.26 190.5 0)
			(effects
				(font
					(size 1.27 1.27)
					(thickness 0.15)
				)
				(justify left bottom)
				(hide yes)
			)
		)
		(property "License" "Apache-2.0"
			(at 175.26 193.04 0)
			(effects
				(font
					(size 1.27 1.27)
					(thickness 0.15)
				)
				(justify left bottom)
				(hide yes)
			)
		)
		(pin "1"
		)
		(instances
			(project "k410t-devboard"
				(path ""
					(reference "#PWR0308")
					(unit 1)
				)
			)
		)
	)
	(symbol
		(lib_id "antmicroResistors0402:R_12k_0402")
		(at 229.87 115.57 90)
		(unit 1)
		(exclude_from_sim no)
		(in_bom yes)
		(on_board yes)
		(dnp no)
		(fields_autoplaced yes)
		(property "Reference" "R248"
			(at 232.41 111.7599 90)
			(effects
				(font
					(size 1.27 1.27)
				)
				(justify right)
			)
		)
		(property "Value" "R_12k_0402"
			(at 242.57 95.25 0)
			(effects
				(font
					(size 1.27 1.27)
					(thickness 0.15)
				)
				(justify left bottom)
				(hide yes)
			)
		)
		(property "Footprint" "antmicro-footprints:R_0402_1005Metric"
			(at 245.11 95.25 0)
			(effects
				(font
					(size 1.27 1.27)
					(thickness 0.15)
				)
				(justify left bottom)
				(hide yes)
			)
		)
		(property "Datasheet" "https://www.bourns.com/docs/product-datasheets/cr.pdf"
			(at 247.65 95.25 0)
			(effects
				(font
					(size 1.27 1.27)
					(thickness 0.15)
				)
				(justify left bottom)
				(hide yes)
			)
		)
		(property "Description" ""
			(at 229.87 115.57 0)
			(effects
				(font
					(size 1.27 1.27)
				)
			)
		)
		(property "Manufacturer" "Bourns"
			(at 252.73 95.25 0)
			(effects
				(font
					(size 1.27 1.27)
					(thickness 0.15)
				)
				(justify left bottom)
				(hide yes)
			)
		)
		(property "MPN" "CR0402-FX-1202GLF"
			(at 250.19 95.25 0)
			(effects
				(font
					(size 1.27 1.27)
					(thickness 0.15)
				)
				(justify left bottom)
				(hide yes)
			)
		)
		(property "Val" "12k"
			(at 232.41 114.2999 90)
			(effects
				(font
					(size 1.27 1.27)
					(thickness 0.15)
				)
				(justify right)
			)
		)
		(property "License" "Apache-2.0"
			(at 255.27 95.25 0)
			(effects
				(font
					(size 1.27 1.27)
					(thickness 0.15)
				)
				(justify left bottom)
				(hide yes)
			)
		)
		(property "Author" "Antmicro"
			(at 257.81 95.25 0)
			(effects
				(font
					(size 1.27 1.27)
					(thickness 0.15)
				)
				(justify left bottom)
				(hide yes)
			)
		)
		(property "Tolerance" "1%"
			(at 240.03 95.25 0)
			(effects
				(font
					(size 1.27 1.27)
				)
				(justify left bottom)
				(hide yes)
			)
		)
		(pin "1"
		)
		(pin "2"
		)
		(instances
			(project "k410t-devboard"
				(path ""
					(reference "R248")
					(unit 1)
				)
			)
		)
	)
	(symbol
		(lib_id "antmicroDiodesRectifiersSingle:BAT54-02V-G3-08")
		(at 347.98 157.48 0)
		(mirror y)
		(unit 1)
		(exclude_from_sim no)
		(in_bom yes)
		(on_board yes)
		(dnp no)
		(property "Reference" "D31"
			(at 343.8525 151.13 0)
			(effects
				(font
					(size 1.27 1.27)
				)
			)
		)
		(property "Value" "BAT54-02V-G3-08"
			(at 343.535 153.67 0)
			(effects
				(font
					(size 1.27 1.27)
					(thickness 0.15)
				)
				(hide yes)
			)
		)
		(property "Footprint" "antmicro-footprints:SOD-523"
			(at 326.39 167.64 0)
			(effects
				(font
					(size 1.27 1.27)
					(thickness 0.15)
				)
				(justify left bottom)
				(hide yes)
			)
		)
		(property "Datasheet" "https://www.vishay.com/docs/85633/bat5402v.pdf"
			(at 326.39 170.18 0)
			(effects
				(font
					(size 1.27 1.27)
					(thickness 0.15)
				)
				(justify left bottom)
				(hide yes)
			)
		)
		(property "Description" ""
			(at 347.98 157.48 0)
			(effects
				(font
					(size 1.27 1.27)
				)
			)
		)
		(property "MPN" "BAT54-02V-G3-08"
			(at 343.8525 153.67 0)
			(effects
				(font
					(size 1.27 1.27)
					(thickness 0.15)
				)
			)
		)
		(property "Manufacturer" "Vishay"
			(at 326.39 175.26 0)
			(effects
				(font
					(size 1.27 1.27)
					(thickness 0.15)
				)
				(justify left bottom)
				(hide yes)
			)
		)
		(property "Author" "Antmicro"
			(at 326.39 177.8 0)
			(effects
				(font
					(size 1.27 1.27)
					(thickness 0.15)
				)
				(justify left bottom)
				(hide yes)
			)
		)
		(property "License" "Apache-2.0"
			(at 326.39 180.34 0)
			(effects
				(font
					(size 1.27 1.27)
					(thickness 0.15)
				)
				(justify left bottom)
				(hide yes)
			)
		)
		(property "Public" "False"
			(at 327.66 175.26 0)
			(effects
				(font
					(size 1.27 1.27)
				)
				(justify left bottom)
				(hide yes)
			)
		)
		(pin "1"
		)
		(pin "2"
		)
		(instances
			(project "k410t-devboard"
				(path ""
					(reference "D31")
					(unit 1)
				)
			)
		)
	)
	(symbol
		(lib_id "antmicroFerriteBeadsandChips:FB_120Z_2A_Murata-BLM18PG_0603")
		(at 327.66 24.13 270)
		(unit 1)
		(exclude_from_sim no)
		(in_bom yes)
		(on_board yes)
		(dnp no)
		(fields_autoplaced yes)
		(property "Reference" "FB10"
			(at 330.2 25.3619 90)
			(effects
				(font
					(size 1.27 1.27)
				)
				(justify left)
			)
		)
		(property "Value" "FB_120Z_2A_Murata-BLM18PG_0603"
			(at 330.835 27.9018 90)
			(effects
				(font
					(size 1.27 1.27)
					(thickness 0.15)
				)
				(justify left)
				(hide yes)
			)
		)
		(property "Footprint" "antmicro-footprints:FB_0603_1608Metric"
			(at 322.58 38.1 0)
			(effects
				(font
					(size 1.27 1.27)
					(thickness 0.15)
				)
				(justify left bottom)
				(hide yes)
			)
		)
		(property "Datasheet" "https://www.murata.com/en-us/products/productdata/8796738650142/ENFA0003.pdf"
			(at 320.04 38.1 0)
			(effects
				(font
					(size 1.27 1.27)
					(thickness 0.15)
				)
				(justify left bottom)
				(hide yes)
			)
		)
		(property "Description" ""
			(at 327.66 24.13 0)
			(effects
				(font
					(size 1.27 1.27)
				)
			)
		)
		(property "MPN" "BLM18PG121SN1D"
			(at 317.5 38.1 0)
			(effects
				(font
					(size 1.27 1.27)
					(thickness 0.15)
				)
				(justify left bottom)
				(hide yes)
			)
		)
		(property "Manufacturer" "Murata"
			(at 314.96 38.1 0)
			(effects
				(font
					(size 1.27 1.27)
					(thickness 0.15)
				)
				(justify left bottom)
				(hide yes)
			)
		)
		(property "Author" "Antmicro"
			(at 312.42 38.1 0)
			(effects
				(font
					(size 1.27 1.27)
					(thickness 0.15)
				)
				(justify left bottom)
				(hide yes)
			)
		)
		(property "License" "Apache-2.0"
			(at 309.88 38.1 0)
			(effects
				(font
					(size 1.27 1.27)
					(thickness 0.15)
				)
				(justify left bottom)
				(hide yes)
			)
		)
		(property "Val" "120Z/2A"
			(at 330.2 27.9019 90)
			(effects
				(font
					(size 1.27 1.27)
				)
				(justify left)
			)
		)
		(property "Current" ""
			(at 304.8 44.45 0)
			(effects
				(font
					(size 1.27 1.27)
					(thickness 0.15)
				)
				(justify left bottom)
				(hide yes)
			)
		)
		(pin "1"
		)
		(pin "2"
		)
		(instances
			(project "k410t-devboard"
				(path ""
					(reference "FB10")
					(unit 1)
				)
			)
		)
	)
	(symbol
		(lib_id "antmicroCapacitors0402:C_22p_0402")
		(at 144.78 129.54 90)
		(unit 1)
		(exclude_from_sim no)
		(in_bom yes)
		(on_board yes)
		(dnp no)
		(property "Reference" "C263"
			(at 145.415 125.095 90)
			(effects
				(font
					(size 1.27 1.27)
				)
				(justify right)
			)
		)
		(property "Value" "C_22p_0402"
			(at 154.94 109.22 0)
			(effects
				(font
					(size 1.27 1.27)
					(thickness 0.15)
				)
				(justify left bottom)
				(hide yes)
			)
		)
		(property "Footprint" "antmicro-footprints:C_0402_1005Metric"
			(at 157.48 109.22 0)
			(effects
				(font
					(size 1.27 1.27)
					(thickness 0.15)
				)
				(justify left bottom)
				(hide yes)
			)
		)
		(property "Datasheet" "https://www.yageo.com/en/Chart/Download/pdf/CC0402JRNPO9BN220"
			(at 160.02 109.22 0)
			(effects
				(font
					(size 1.27 1.27)
					(thickness 0.15)
				)
				(justify left bottom)
				(hide yes)
			)
		)
		(property "Description" ""
			(at 144.78 129.54 0)
			(effects
				(font
					(size 1.27 1.27)
				)
			)
		)
		(property "Manufacturer" "YAGEO"
			(at 165.1 109.22 0)
			(effects
				(font
					(size 1.27 1.27)
					(thickness 0.15)
				)
				(justify left bottom)
				(hide yes)
			)
		)
		(property "MPN" "CC0402JRNPO9BN220"
			(at 162.56 109.22 0)
			(effects
				(font
					(size 1.27 1.27)
					(thickness 0.15)
				)
				(justify left bottom)
				(hide yes)
			)
		)
		(property "Val" "22p"
			(at 145.415 128.905 90)
			(effects
				(font
					(size 1.27 1.27)
					(thickness 0.15)
				)
				(justify right)
			)
		)
		(property "License" "Apache-2.0"
			(at 167.64 109.22 0)
			(effects
				(font
					(size 1.27 1.27)
					(thickness 0.15)
				)
				(justify left bottom)
				(hide yes)
			)
		)
		(property "Author" "Antmicro"
			(at 170.18 109.22 0)
			(effects
				(font
					(size 1.27 1.27)
					(thickness 0.15)
				)
				(justify left bottom)
				(hide yes)
			)
		)
		(property "Voltage" ""
			(at 172.72 109.22 0)
			(effects
				(font
					(size 1.27 1.27)
				)
				(justify left bottom)
				(hide yes)
			)
		)
		(property "Dielectric" ""
			(at 175.26 109.22 0)
			(effects
				(font
					(size 1.27 1.27)
				)
				(justify left bottom)
				(hide yes)
			)
		)
		(pin "1"
		)
		(pin "2"
		)
		(instances
			(project "k410t-devboard"
				(path ""
					(reference "C263")
					(unit 1)
				)
			)
		)
	)
	(symbol
		(lib_id "antmicropower:GND")
		(at 317.5 44.45 0)
		(unit 1)
		(exclude_from_sim no)
		(in_bom yes)
		(on_board yes)
		(dnp no)
		(fields_autoplaced yes)
		(property "Reference" "#PWR0341"
			(at 317.5 50.8 0)
			(effects
				(font
					(size 1.27 1.27)
				)
				(hide yes)
			)
		)
		(property "Value" "GND"
			(at 317.5 48.26 0)
			(effects
				(font
					(size 1.27 1.27)
				)
			)
		)
		(property "Footprint" ""
			(at 326.39 52.07 0)
			(effects
				(font
					(size 1.27 1.27)
					(thickness 0.15)
				)
				(justify left bottom)
				(hide yes)
			)
		)
		(property "Datasheet" ""
			(at 326.39 57.15 0)
			(effects
				(font
					(size 1.27 1.27)
					(thickness 0.15)
				)
				(justify left bottom)
				(hide yes)
			)
		)
		(property "Description" ""
			(at 317.5 44.45 0)
			(effects
				(font
					(size 1.27 1.27)
				)
			)
		)
		(property "Author" "Antmicro"
			(at 326.39 52.07 0)
			(effects
				(font
					(size 1.27 1.27)
					(thickness 0.15)
				)
				(justify left bottom)
				(hide yes)
			)
		)
		(property "License" "Apache-2.0"
			(at 326.39 54.61 0)
			(effects
				(font
					(size 1.27 1.27)
					(thickness 0.15)
				)
				(justify left bottom)
				(hide yes)
			)
		)
		(pin "1"
		)
		(instances
			(project "k410t-devboard"
				(path ""
					(reference "#PWR0341")
					(unit 1)
				)
			)
		)
	)
	(symbol
		(lib_id "antmicroResistors0402:R_10k_0402")
		(at 52.07 69.85 0)
		(mirror x)
		(unit 1)
		(exclude_from_sim no)
		(in_bom yes)
		(on_board yes)
		(dnp no)
		(property "Reference" "R204"
			(at 59.69 68.58 0)
			(effects
				(font
					(size 1.27 1.27)
				)
			)
		)
		(property "Value" "R_10k_0402"
			(at 72.39 57.15 0)
			(effects
				(font
					(size 1.27 1.27)
					(thickness 0.15)
				)
				(justify left bottom)
				(hide yes)
			)
		)
		(property "Footprint" "antmicro-footprints:R_0402_1005Metric"
			(at 72.39 54.61 0)
			(effects
				(font
					(size 1.27 1.27)
					(thickness 0.15)
				)
				(justify left bottom)
				(hide yes)
			)
		)
		(property "Datasheet" "https://www.bourns.com/docs/product-datasheets/cr.pdf"
			(at 72.39 52.07 0)
			(effects
				(font
					(size 1.27 1.27)
					(thickness 0.15)
				)
				(justify left bottom)
				(hide yes)
			)
		)
		(property "Description" ""
			(at 52.07 69.85 0)
			(effects
				(font
					(size 1.27 1.27)
				)
			)
		)
		(property "Manufacturer" "Bourns"
			(at 72.39 46.99 0)
			(effects
				(font
					(size 1.27 1.27)
					(thickness 0.15)
				)
				(justify left bottom)
				(hide yes)
			)
		)
		(property "MPN" "CR0402-FX-1002GLF"
			(at 72.39 49.53 0)
			(effects
				(font
					(size 1.27 1.27)
					(thickness 0.15)
				)
				(justify left bottom)
				(hide yes)
			)
		)
		(property "Val" "10k"
			(at 50.165 68.58 0)
			(effects
				(font
					(size 1.27 1.27)
					(thickness 0.15)
				)
			)
		)
		(property "License" "Apache-2.0"
			(at 72.39 44.45 0)
			(effects
				(font
					(size 1.27 1.27)
					(thickness 0.15)
				)
				(justify left bottom)
				(hide yes)
			)
		)
		(property "Author" "Antmicro"
			(at 72.39 41.91 0)
			(effects
				(font
					(size 1.27 1.27)
					(thickness 0.15)
				)
				(justify left bottom)
				(hide yes)
			)
		)
		(property "Tolerance" "1%"
			(at 72.39 59.69 0)
			(effects
				(font
					(size 1.27 1.27)
				)
				(justify left bottom)
				(hide yes)
			)
		)
		(pin "1"
		)
		(pin "2"
		)
		(instances
			(project "k410t-devboard"
				(path ""
					(reference "R204")
					(unit 1)
				)
			)
		)
	)
	(symbol
		(lib_id "antmicroResistors0402:R_0R_0402")
		(at 342.9 179.07 0)
		(unit 1)
		(exclude_from_sim no)
		(in_bom yes)
		(on_board yes)
		(dnp no)
		(property "Reference" "R259"
			(at 350.52 177.8 0)
			(effects
				(font
					(size 1.27 1.27)
				)
			)
		)
		(property "Value" "R_0R_0402"
			(at 363.22 191.77 0)
			(effects
				(font
					(size 1.27 1.27)
					(thickness 0.15)
				)
				(justify left bottom)
				(hide yes)
			)
		)
		(property "Footprint" "antmicro-footprints:R_0402_1005Metric"
			(at 363.22 194.31 0)
			(effects
				(font
					(size 1.27 1.27)
					(thickness 0.15)
				)
				(justify left bottom)
				(hide yes)
			)
		)
		(property "Datasheet" "https://industrial.panasonic.com/cdbs/www-data/pdf/RDA0000/AOA0000C301.pdf"
			(at 363.22 196.85 0)
			(effects
				(font
					(size 1.27 1.27)
					(thickness 0.15)
				)
				(justify left bottom)
				(hide yes)
			)
		)
		(property "Description" ""
			(at 342.9 179.07 0)
			(effects
				(font
					(size 1.27 1.27)
				)
			)
		)
		(property "Manufacturer" "Panasonic"
			(at 363.22 201.93 0)
			(effects
				(font
					(size 1.27 1.27)
					(thickness 0.15)
				)
				(justify left bottom)
				(hide yes)
			)
		)
		(property "MPN" "ERJ2GE0R00X"
			(at 363.22 199.39 0)
			(effects
				(font
					(size 1.27 1.27)
					(thickness 0.15)
				)
				(justify left bottom)
				(hide yes)
			)
		)
		(property "Val" "0R"
			(at 341.63 177.8 0)
			(effects
				(font
					(size 1.27 1.27)
					(thickness 0.15)
				)
			)
		)
		(property "License" "Apache-2.0"
			(at 363.22 204.47 0)
			(effects
				(font
					(size 1.27 1.27)
					(thickness 0.15)
				)
				(justify left bottom)
				(hide yes)
			)
		)
		(property "Author" "Antmicro"
			(at 363.22 207.01 0)
			(effects
				(font
					(size 1.27 1.27)
					(thickness 0.15)
				)
				(justify left bottom)
				(hide yes)
			)
		)
		(property "Tolerance" "~"
			(at 363.22 189.23 0)
			(effects
				(font
					(size 1.27 1.27)
				)
				(justify left bottom)
				(hide yes)
			)
		)
		(property "Current" "1A"
			(at 363.22 209.55 0)
			(effects
				(font
					(size 1.27 1.27)
					(thickness 0.15)
				)
				(justify left bottom)
				(hide yes)
			)
		)
		(pin "1"
		)
		(pin "2"
		)
		(instances
			(project "k410t-devboard"
				(path ""
					(reference "R259")
					(unit 1)
				)
			)
		)
	)
	(symbol
		(lib_id "antmicroResistors0402:R_2k2_0402")
		(at 52.07 88.9 0)
		(unit 1)
		(exclude_from_sim no)
		(in_bom no)
		(on_board yes)
		(dnp yes)
		(property "Reference" "R209"
			(at 59.69 87.63 0)
			(effects
				(font
					(size 1.27 1.27)
				)
			)
		)
		(property "Value" "R_2k2_0402"
			(at 72.39 101.6 0)
			(effects
				(font
					(size 1.27 1.27)
					(thickness 0.15)
				)
				(justify left bottom)
				(hide yes)
			)
		)
		(property "Footprint" "antmicro-footprints:R_0402_1005Metric"
			(at 72.39 104.14 0)
			(effects
				(font
					(size 1.27 1.27)
					(thickness 0.15)
				)
				(justify left bottom)
				(hide yes)
			)
		)
		(property "Datasheet" "https://www.bourns.com/docs/product-datasheets/cr.pdf"
			(at 72.39 106.68 0)
			(effects
				(font
					(size 1.27 1.27)
					(thickness 0.15)
				)
				(justify left bottom)
				(hide yes)
			)
		)
		(property "Description" ""
			(at 52.07 88.9 0)
			(effects
				(font
					(size 1.27 1.27)
				)
			)
		)
		(property "Manufacturer" "Bourns"
			(at 72.39 111.76 0)
			(effects
				(font
					(size 1.27 1.27)
					(thickness 0.15)
				)
				(justify left bottom)
				(hide yes)
			)
		)
		(property "MPN" "CR0402-FX-2201GLF"
			(at 72.39 109.22 0)
			(effects
				(font
					(size 1.27 1.27)
					(thickness 0.15)
				)
				(justify left bottom)
				(hide yes)
			)
		)
		(property "Val" "2k2"
			(at 50.165 87.63 0)
			(effects
				(font
					(size 1.27 1.27)
					(thickness 0.15)
				)
			)
		)
		(property "DNP" "DNP"
			(at 54.61 88.9 0)
			(effects
				(font
					(size 1.27 1.27)
				)
			)
		)
		(property "License" "Apache-2.0"
			(at 72.39 114.3 0)
			(effects
				(font
					(size 1.27 1.27)
					(thickness 0.15)
				)
				(justify left bottom)
				(hide yes)
			)
		)
		(property "Author" "Antmicro"
			(at 72.39 116.84 0)
			(effects
				(font
					(size 1.27 1.27)
					(thickness 0.15)
				)
				(justify left bottom)
				(hide yes)
			)
		)
		(property "Tolerance" "1%"
			(at 72.39 99.06 0)
			(effects
				(font
					(size 1.27 1.27)
				)
				(justify left bottom)
				(hide yes)
			)
		)
		(pin "1"
		)
		(pin "2"
		)
		(instances
			(project "k410t-devboard"
				(path ""
					(reference "R209")
					(unit 1)
				)
			)
		)
	)
	(symbol
		(lib_id "antmicroResistors0402:R_2k2_0402")
		(at 52.07 111.76 0)
		(unit 1)
		(exclude_from_sim no)
		(in_bom yes)
		(on_board yes)
		(dnp no)
		(property "Reference" "R217"
			(at 59.69 110.49 0)
			(effects
				(font
					(size 1.27 1.27)
				)
			)
		)
		(property "Value" "R_2k2_0402"
			(at 72.39 124.46 0)
			(effects
				(font
					(size 1.27 1.27)
					(thickness 0.15)
				)
				(justify left bottom)
				(hide yes)
			)
		)
		(property "Footprint" "antmicro-footprints:R_0402_1005Metric"
			(at 72.39 127 0)
			(effects
				(font
					(size 1.27 1.27)
					(thickness 0.15)
				)
				(justify left bottom)
				(hide yes)
			)
		)
		(property "Datasheet" "https://www.bourns.com/docs/product-datasheets/cr.pdf"
			(at 72.39 129.54 0)
			(effects
				(font
					(size 1.27 1.27)
					(thickness 0.15)
				)
				(justify left bottom)
				(hide yes)
			)
		)
		(property "Description" ""
			(at 52.07 111.76 0)
			(effects
				(font
					(size 1.27 1.27)
				)
			)
		)
		(property "Manufacturer" "Bourns"
			(at 72.39 134.62 0)
			(effects
				(font
					(size 1.27 1.27)
					(thickness 0.15)
				)
				(justify left bottom)
				(hide yes)
			)
		)
		(property "MPN" "CR0402-FX-2201GLF"
			(at 72.39 132.08 0)
			(effects
				(font
					(size 1.27 1.27)
					(thickness 0.15)
				)
				(justify left bottom)
				(hide yes)
			)
		)
		(property "Val" "2k2"
			(at 50.165 110.49 0)
			(effects
				(font
					(size 1.27 1.27)
					(thickness 0.15)
				)
			)
		)
		(property "License" "Apache-2.0"
			(at 72.39 137.16 0)
			(effects
				(font
					(size 1.27 1.27)
					(thickness 0.15)
				)
				(justify left bottom)
				(hide yes)
			)
		)
		(property "Author" "Antmicro"
			(at 72.39 139.7 0)
			(effects
				(font
					(size 1.27 1.27)
					(thickness 0.15)
				)
				(justify left bottom)
				(hide yes)
			)
		)
		(property "Tolerance" "1%"
			(at 72.39 121.92 0)
			(effects
				(font
					(size 1.27 1.27)
				)
				(justify left bottom)
				(hide yes)
			)
		)
		(pin "1"
		)
		(pin "2"
		)
		(instances
			(project "k410t-devboard"
				(path ""
					(reference "R217")
					(unit 1)
				)
			)
		)
	)
	(symbol
		(lib_id "antmicroResistors0402:R_1M_0402")
		(at 153.67 118.11 90)
		(unit 1)
		(exclude_from_sim no)
		(in_bom yes)
		(on_board yes)
		(dnp no)
		(fields_autoplaced yes)
		(property "Reference" "R242"
			(at 155.575 114.2999 90)
			(effects
				(font
					(size 1.27 1.27)
				)
				(justify right)
			)
		)
		(property "Value" "R_1M_0402"
			(at 166.37 97.79 0)
			(effects
				(font
					(size 1.27 1.27)
					(thickness 0.15)
				)
				(justify left bottom)
				(hide yes)
			)
		)
		(property "Footprint" "antmicro-footprints:R_0402_1005Metric"
			(at 168.91 97.79 0)
			(effects
				(font
					(size 1.27 1.27)
					(thickness 0.15)
				)
				(justify left bottom)
				(hide yes)
			)
		)
		(property "Datasheet" "https://www.bourns.com/docs/product-datasheets/cr.pdf"
			(at 171.45 97.79 0)
			(effects
				(font
					(size 1.27 1.27)
					(thickness 0.15)
				)
				(justify left bottom)
				(hide yes)
			)
		)
		(property "Description" ""
			(at 153.67 118.11 0)
			(effects
				(font
					(size 1.27 1.27)
				)
			)
		)
		(property "Manufacturer" "Bourns"
			(at 176.53 97.79 0)
			(effects
				(font
					(size 1.27 1.27)
					(thickness 0.15)
				)
				(justify left bottom)
				(hide yes)
			)
		)
		(property "MPN" "CR0402-FX-1004GLF"
			(at 173.99 97.79 0)
			(effects
				(font
					(size 1.27 1.27)
					(thickness 0.15)
				)
				(justify left bottom)
				(hide yes)
			)
		)
		(property "Val" "1M"
			(at 155.575 116.8399 90)
			(effects
				(font
					(size 1.27 1.27)
					(thickness 0.15)
				)
				(justify right)
			)
		)
		(property "License" "Apache-2.0"
			(at 179.07 97.79 0)
			(effects
				(font
					(size 1.27 1.27)
					(thickness 0.15)
				)
				(justify left bottom)
				(hide yes)
			)
		)
		(property "Author" "Antmicro"
			(at 181.61 97.79 0)
			(effects
				(font
					(size 1.27 1.27)
					(thickness 0.15)
				)
				(justify left bottom)
				(hide yes)
			)
		)
		(property "Tolerance" "1%"
			(at 163.83 97.79 0)
			(effects
				(font
					(size 1.27 1.27)
				)
				(justify left bottom)
				(hide yes)
			)
		)
		(pin "1"
		)
		(pin "2"
		)
		(instances
			(project "k410t-devboard"
				(path ""
					(reference "R242")
					(unit 1)
				)
			)
		)
	)
	(symbol
		(lib_id "antmicroResistors0402:R_1k_0402")
		(at 116.84 66.04 0)
		(unit 1)
		(exclude_from_sim no)
		(in_bom yes)
		(on_board yes)
		(dnp no)
		(property "Reference" "R240"
			(at 124.46 64.77 0)
			(effects
				(font
					(size 1.27 1.27)
				)
			)
		)
		(property "Value" "R_1k_0402"
			(at 137.16 78.74 0)
			(effects
				(font
					(size 1.27 1.27)
					(thickness 0.15)
				)
				(justify left bottom)
				(hide yes)
			)
		)
		(property "Footprint" "antmicro-footprints:R_0402_1005Metric"
			(at 137.16 81.28 0)
			(effects
				(font
					(size 1.27 1.27)
					(thickness 0.15)
				)
				(justify left bottom)
				(hide yes)
			)
		)
		(property "Datasheet" "https://www.bourns.com/docs/product-datasheets/cr.pdf"
			(at 137.16 83.82 0)
			(effects
				(font
					(size 1.27 1.27)
					(thickness 0.15)
				)
				(justify left bottom)
				(hide yes)
			)
		)
		(property "Description" ""
			(at 116.84 66.04 0)
			(effects
				(font
					(size 1.27 1.27)
				)
			)
		)
		(property "Manufacturer" "Bourns"
			(at 137.16 88.9 0)
			(effects
				(font
					(size 1.27 1.27)
					(thickness 0.15)
				)
				(justify left bottom)
				(hide yes)
			)
		)
		(property "MPN" "CR0402-FX-1001GLF"
			(at 137.16 86.36 0)
			(effects
				(font
					(size 1.27 1.27)
					(thickness 0.15)
				)
				(justify left bottom)
				(hide yes)
			)
		)
		(property "Val" "1k"
			(at 115.57 64.77 0)
			(effects
				(font
					(size 1.27 1.27)
					(thickness 0.15)
				)
			)
		)
		(property "License" "Apache-2.0"
			(at 137.16 91.44 0)
			(effects
				(font
					(size 1.27 1.27)
					(thickness 0.15)
				)
				(justify left bottom)
				(hide yes)
			)
		)
		(property "Author" "Antmicro"
			(at 137.16 93.98 0)
			(effects
				(font
					(size 1.27 1.27)
					(thickness 0.15)
				)
				(justify left bottom)
				(hide yes)
			)
		)
		(property "Tolerance" "1%"
			(at 137.16 76.2 0)
			(effects
				(font
					(size 1.27 1.27)
				)
				(justify left bottom)
				(hide yes)
			)
		)
		(pin "1"
		)
		(pin "2"
		)
		(instances
			(project "k410t-devboard"
				(path ""
					(reference "R240")
					(unit 1)
				)
			)
		)
	)
	(symbol
		(lib_id "antmicroResistors0402:R_10k_0402")
		(at 52.07 227.33 0)
		(mirror x)
		(unit 1)
		(exclude_from_sim no)
		(in_bom yes)
		(on_board yes)
		(dnp no)
		(property "Reference" "R219"
			(at 59.69 226.06 0)
			(effects
				(font
					(size 1.27 1.27)
				)
			)
		)
		(property "Value" "R_10k_0402"
			(at 72.39 214.63 0)
			(effects
				(font
					(size 1.27 1.27)
					(thickness 0.15)
				)
				(justify left bottom)
				(hide yes)
			)
		)
		(property "Footprint" "antmicro-footprints:R_0402_1005Metric"
			(at 72.39 212.09 0)
			(effects
				(font
					(size 1.27 1.27)
					(thickness 0.15)
				)
				(justify left bottom)
				(hide yes)
			)
		)
		(property "Datasheet" "https://www.bourns.com/docs/product-datasheets/cr.pdf"
			(at 72.39 209.55 0)
			(effects
				(font
					(size 1.27 1.27)
					(thickness 0.15)
				)
				(justify left bottom)
				(hide yes)
			)
		)
		(property "Description" ""
			(at 52.07 227.33 0)
			(effects
				(font
					(size 1.27 1.27)
				)
			)
		)
		(property "Manufacturer" "Bourns"
			(at 72.39 204.47 0)
			(effects
				(font
					(size 1.27 1.27)
					(thickness 0.15)
				)
				(justify left bottom)
				(hide yes)
			)
		)
		(property "MPN" "CR0402-FX-1002GLF"
			(at 72.39 207.01 0)
			(effects
				(font
					(size 1.27 1.27)
					(thickness 0.15)
				)
				(justify left bottom)
				(hide yes)
			)
		)
		(property "Val" "10k"
			(at 50.165 226.06 0)
			(effects
				(font
					(size 1.27 1.27)
					(thickness 0.15)
				)
			)
		)
		(property "License" "Apache-2.0"
			(at 72.39 201.93 0)
			(effects
				(font
					(size 1.27 1.27)
					(thickness 0.15)
				)
				(justify left bottom)
				(hide yes)
			)
		)
		(property "Author" "Antmicro"
			(at 72.39 199.39 0)
			(effects
				(font
					(size 1.27 1.27)
					(thickness 0.15)
				)
				(justify left bottom)
				(hide yes)
			)
		)
		(property "Tolerance" "1%"
			(at 72.39 217.17 0)
			(effects
				(font
					(size 1.27 1.27)
				)
				(justify left bottom)
				(hide yes)
			)
		)
		(pin "1"
		)
		(pin "2"
		)
		(instances
			(project "k410t-devboard"
				(path ""
					(reference "R219")
					(unit 1)
				)
			)
		)
	)
	(symbol
		(lib_id "antmicropower:PWR_FLAG")
		(at 114.3 35.56 90)
		(unit 1)
		(exclude_from_sim no)
		(in_bom yes)
		(on_board yes)
		(dnp no)
		(fields_autoplaced yes)
		(property "Reference" "#FLG010"
			(at 112.395 35.56 0)
			(effects
				(font
					(size 1.27 1.27)
				)
				(hide yes)
			)
		)
		(property "Value" "PWR_FLAG"
			(at 111.125 35.5599 90)
			(effects
				(font
					(size 1.27 1.27)
				)
				(justify left)
			)
		)
		(property "Footprint" ""
			(at 114.3 35.56 0)
			(effects
				(font
					(size 1.27 1.27)
				)
				(hide yes)
			)
		)
		(property "Datasheet" ""
			(at 114.3 35.56 0)
			(effects
				(font
					(size 1.27 1.27)
				)
				(hide yes)
			)
		)
		(property "Description" ""
			(at 114.3 35.56 0)
			(effects
				(font
					(size 1.27 1.27)
				)
			)
		)
		(pin "1"
		)
		(instances
			(project "k410t-devboard"
				(path ""
					(reference "#FLG010")
					(unit 1)
				)
			)
		)
	)
	(symbol
		(lib_id "antmicropower:PWR_FLAG")
		(at 203.2 154.94 0)
		(unit 1)
		(exclude_from_sim no)
		(in_bom yes)
		(on_board yes)
		(dnp no)
		(fields_autoplaced yes)
		(property "Reference" "#FLG011"
			(at 203.2 153.035 0)
			(effects
				(font
					(size 1.27 1.27)
				)
				(hide yes)
			)
		)
		(property "Value" "PWR_FLAG"
			(at 203.2 151.13 0)
			(effects
				(font
					(size 1.27 1.27)
				)
			)
		)
		(property "Footprint" ""
			(at 203.2 154.94 0)
			(effects
				(font
					(size 1.27 1.27)
				)
				(hide yes)
			)
		)
		(property "Datasheet" ""
			(at 203.2 154.94 0)
			(effects
				(font
					(size 1.27 1.27)
				)
				(hide yes)
			)
		)
		(property "Description" ""
			(at 203.2 154.94 0)
			(effects
				(font
					(size 1.27 1.27)
				)
			)
		)
		(pin "1"
		)
		(instances
			(project "k410t-devboard"
				(path ""
					(reference "#FLG011")
					(unit 1)
				)
			)
		)
	)
	(symbol
		(lib_id "antmicroCapacitors0402:C_100n_0402")
		(at 195.58 162.56 90)
		(unit 1)
		(exclude_from_sim no)
		(in_bom yes)
		(on_board yes)
		(dnp no)
		(property "Reference" "C270"
			(at 196.215 158.115 90)
			(effects
				(font
					(size 1.27 1.27)
				)
				(justify right)
			)
		)
		(property "Value" "C_100n_0402"
			(at 205.74 142.24 0)
			(effects
				(font
					(size 1.27 1.27)
					(thickness 0.15)
				)
				(justify left bottom)
				(hide yes)
			)
		)
		(property "Footprint" "antmicro-footprints:C_0402_1005Metric"
			(at 208.28 142.24 0)
			(effects
				(font
					(size 1.27 1.27)
					(thickness 0.15)
				)
				(justify left bottom)
				(hide yes)
			)
		)
		(property "Datasheet" "https://www.murata.com/products/productdetail?partno=GRM155R61H104KE14%23"
			(at 210.82 142.24 0)
			(effects
				(font
					(size 1.27 1.27)
					(thickness 0.15)
				)
				(justify left bottom)
				(hide yes)
			)
		)
		(property "Description" ""
			(at 195.58 162.56 0)
			(effects
				(font
					(size 1.27 1.27)
				)
			)
		)
		(property "Manufacturer" "Murata"
			(at 215.9 142.24 0)
			(effects
				(font
					(size 1.27 1.27)
					(thickness 0.15)
				)
				(justify left bottom)
				(hide yes)
			)
		)
		(property "MPN" "GRM155R61H104KE14D"
			(at 213.36 142.24 0)
			(effects
				(font
					(size 1.27 1.27)
					(thickness 0.15)
				)
				(justify left bottom)
				(hide yes)
			)
		)
		(property "Val" "100n"
			(at 196.215 161.925 90)
			(effects
				(font
					(size 1.27 1.27)
					(thickness 0.15)
				)
				(justify right)
			)
		)
		(property "License" "Apache-2.0"
			(at 218.44 142.24 0)
			(effects
				(font
					(size 1.27 1.27)
					(thickness 0.15)
				)
				(justify left bottom)
				(hide yes)
			)
		)
		(property "Author" "Antmicro"
			(at 220.98 142.24 0)
			(effects
				(font
					(size 1.27 1.27)
					(thickness 0.15)
				)
				(justify left bottom)
				(hide yes)
			)
		)
		(property "Voltage" "50V"
			(at 223.52 142.24 0)
			(effects
				(font
					(size 1.27 1.27)
				)
				(justify left bottom)
				(hide yes)
			)
		)
		(property "Dielectric" "X5R"
			(at 226.06 142.24 0)
			(effects
				(font
					(size 1.27 1.27)
				)
				(justify left bottom)
				(hide yes)
			)
		)
		(pin "1"
		)
		(pin "2"
		)
		(instances
			(project "k410t-devboard"
				(path ""
					(reference "C270")
					(unit 1)
				)
			)
		)
	)
	(symbol
		(lib_id "antmicroCapacitors0402:C_10u_0402")
		(at 259.08 43.18 90)
		(unit 1)
		(exclude_from_sim no)
		(in_bom yes)
		(on_board yes)
		(dnp no)
		(property "Reference" "C285"
			(at 259.715 38.735 90)
			(effects
				(font
					(size 1.27 1.27)
				)
				(justify right)
			)
		)
		(property "Value" "C_10u_0402"
			(at 269.24 22.86 0)
			(effects
				(font
					(size 1.27 1.27)
					(thickness 0.15)
				)
				(justify left bottom)
				(hide yes)
			)
		)
		(property "Footprint" "antmicro-footprints:C_0402_1005Metric"
			(at 271.78 22.86 0)
			(effects
				(font
					(size 1.27 1.27)
					(thickness 0.15)
				)
				(justify left bottom)
				(hide yes)
			)
		)
		(property "Datasheet" "https://www.yageo.com/en/Chart/Download/pdf/CC0402MRX5R5BB106"
			(at 274.32 22.86 0)
			(effects
				(font
					(size 1.27 1.27)
					(thickness 0.15)
				)
				(justify left bottom)
				(hide yes)
			)
		)
		(property "Description" ""
			(at 259.08 43.18 0)
			(effects
				(font
					(size 1.27 1.27)
				)
			)
		)
		(property "Manufacturer" "YAGEO"
			(at 279.4 22.86 0)
			(effects
				(font
					(size 1.27 1.27)
					(thickness 0.15)
				)
				(justify left bottom)
				(hide yes)
			)
		)
		(property "MPN" "CC0402MRX5R5BB106"
			(at 276.86 22.86 0)
			(effects
				(font
					(size 1.27 1.27)
					(thickness 0.15)
				)
				(justify left bottom)
				(hide yes)
			)
		)
		(property "Val" "10u"
			(at 259.715 42.545 90)
			(effects
				(font
					(size 1.27 1.27)
					(thickness 0.15)
				)
				(justify right)
			)
		)
		(property "License" "Apache-2.0"
			(at 281.94 22.86 0)
			(effects
				(font
					(size 1.27 1.27)
					(thickness 0.15)
				)
				(justify left bottom)
				(hide yes)
			)
		)
		(property "Author" "Antmicro"
			(at 284.48 22.86 0)
			(effects
				(font
					(size 1.27 1.27)
					(thickness 0.15)
				)
				(justify left bottom)
				(hide yes)
			)
		)
		(property "Voltage" ""
			(at 287.02 22.86 0)
			(effects
				(font
					(size 1.27 1.27)
				)
				(justify left bottom)
				(hide yes)
			)
		)
		(property "Dielectric" ""
			(at 289.56 22.86 0)
			(effects
				(font
					(size 1.27 1.27)
				)
				(justify left bottom)
				(hide yes)
			)
		)
		(pin "1"
		)
		(pin "2"
		)
		(instances
			(project "k410t-devboard"
				(path ""
					(reference "C285")
					(unit 1)
				)
			)
		)
	)
	(symbol
		(lib_id "antmicroResistors0402:R_2k2_0402")
		(at 52.07 260.35 0)
		(unit 1)
		(exclude_from_sim no)
		(in_bom no)
		(on_board yes)
		(dnp yes)
		(property "Reference" "R228"
			(at 59.69 259.08 0)
			(effects
				(font
					(size 1.27 1.27)
				)
			)
		)
		(property "Value" "R_2k2_0402"
			(at 72.39 273.05 0)
			(effects
				(font
					(size 1.27 1.27)
					(thickness 0.15)
				)
				(justify left bottom)
				(hide yes)
			)
		)
		(property "Footprint" "antmicro-footprints:R_0402_1005Metric"
			(at 72.39 275.59 0)
			(effects
				(font
					(size 1.27 1.27)
					(thickness 0.15)
				)
				(justify left bottom)
				(hide yes)
			)
		)
		(property "Datasheet" "https://www.bourns.com/docs/product-datasheets/cr.pdf"
			(at 72.39 278.13 0)
			(effects
				(font
					(size 1.27 1.27)
					(thickness 0.15)
				)
				(justify left bottom)
				(hide yes)
			)
		)
		(property "Description" ""
			(at 52.07 260.35 0)
			(effects
				(font
					(size 1.27 1.27)
				)
			)
		)
		(property "Manufacturer" "Bourns"
			(at 72.39 283.21 0)
			(effects
				(font
					(size 1.27 1.27)
					(thickness 0.15)
				)
				(justify left bottom)
				(hide yes)
			)
		)
		(property "MPN" "CR0402-FX-2201GLF"
			(at 72.39 280.67 0)
			(effects
				(font
					(size 1.27 1.27)
					(thickness 0.15)
				)
				(justify left bottom)
				(hide yes)
			)
		)
		(property "Val" "2k2"
			(at 50.165 259.08 0)
			(effects
				(font
					(size 1.27 1.27)
					(thickness 0.15)
				)
			)
		)
		(property "DNP" "DNP"
			(at 54.61 260.35 0)
			(effects
				(font
					(size 1.27 1.27)
				)
			)
		)
		(property "License" "Apache-2.0"
			(at 72.39 285.75 0)
			(effects
				(font
					(size 1.27 1.27)
					(thickness 0.15)
				)
				(justify left bottom)
				(hide yes)
			)
		)
		(property "Author" "Antmicro"
			(at 72.39 288.29 0)
			(effects
				(font
					(size 1.27 1.27)
					(thickness 0.15)
				)
				(justify left bottom)
				(hide yes)
			)
		)
		(property "Tolerance" "1%"
			(at 72.39 270.51 0)
			(effects
				(font
					(size 1.27 1.27)
				)
				(justify left bottom)
				(hide yes)
			)
		)
		(pin "1"
		)
		(pin "2"
		)
		(instances
			(project "k410t-devboard"
				(path ""
					(reference "R228")
					(unit 1)
				)
			)
		)
	)
	(symbol
		(lib_id "antmicropower:GND")
		(at 106.68 241.3 0)
		(unit 1)
		(exclude_from_sim no)
		(in_bom yes)
		(on_board yes)
		(dnp no)
		(property "Reference" "#PWR0286"
			(at 106.68 247.65 0)
			(effects
				(font
					(size 1.27 1.27)
				)
				(hide yes)
			)
		)
		(property "Value" "GND"
			(at 106.68 245.11 0)
			(effects
				(font
					(size 1.27 1.27)
				)
			)
		)
		(property "Footprint" ""
			(at 115.57 248.92 0)
			(effects
				(font
					(size 1.27 1.27)
					(thickness 0.15)
				)
				(justify left bottom)
				(hide yes)
			)
		)
		(property "Datasheet" ""
			(at 115.57 254 0)
			(effects
				(font
					(size 1.27 1.27)
					(thickness 0.15)
				)
				(justify left bottom)
				(hide yes)
			)
		)
		(property "Description" ""
			(at 106.68 241.3 0)
			(effects
				(font
					(size 1.27 1.27)
				)
			)
		)
		(property "Author" "Antmicro"
			(at 115.57 248.92 0)
			(effects
				(font
					(size 1.27 1.27)
					(thickness 0.15)
				)
				(justify left bottom)
				(hide yes)
			)
		)
		(property "License" "Apache-2.0"
			(at 115.57 251.46 0)
			(effects
				(font
					(size 1.27 1.27)
					(thickness 0.15)
				)
				(justify left bottom)
				(hide yes)
			)
		)
		(pin "1"
		)
		(instances
			(project "k410t-devboard"
				(path ""
					(reference "#PWR0286")
					(unit 1)
				)
			)
		)
	)
	(symbol
		(lib_id "antmicropower:+1V8")
		(at 68.58 223.52 0)
		(unit 1)
		(exclude_from_sim no)
		(in_bom yes)
		(on_board yes)
		(dnp no)
		(property "Reference" "#PWR0254"
			(at 68.58 227.33 0)
			(effects
				(font
					(size 1.27 1.27)
				)
				(hide yes)
			)
		)
		(property "Value" "+1V8"
			(at 68.58 219.964 0)
			(effects
				(font
					(size 1.27 1.27)
				)
			)
		)
		(property "Footprint" ""
			(at 83.82 231.14 0)
			(effects
				(font
					(size 1.27 1.27)
					(thickness 0.15)
				)
				(justify left bottom)
				(hide yes)
			)
		)
		(property "Datasheet" ""
			(at 83.82 233.68 0)
			(effects
				(font
					(size 1.27 1.27)
					(thickness 0.15)
				)
				(justify left bottom)
				(hide yes)
			)
		)
		(property "Description" ""
			(at 68.58 223.52 0)
			(effects
				(font
					(size 1.27 1.27)
				)
			)
		)
		(property "Author" "Antmicro"
			(at 83.82 231.14 0)
			(effects
				(font
					(size 1.27 1.27)
					(thickness 0.15)
				)
				(justify left bottom)
				(hide yes)
			)
		)
		(property "License" "Apache-2.0"
			(at 83.82 233.68 0)
			(effects
				(font
					(size 1.27 1.27)
					(thickness 0.15)
				)
				(justify left bottom)
				(hide yes)
			)
		)
		(pin "1"
		)
		(instances
			(project "k410t-devboard"
				(path ""
					(reference "#PWR0254")
					(unit 1)
				)
			)
		)
	)
	(symbol
		(lib_id "antmicroResistors0402:R_2k2_0402")
		(at 52.07 256.54 0)
		(unit 1)
		(exclude_from_sim no)
		(in_bom no)
		(on_board yes)
		(dnp yes)
		(property "Reference" "R227"
			(at 59.69 255.27 0)
			(effects
				(font
					(size 1.27 1.27)
				)
			)
		)
		(property "Value" "R_2k2_0402"
			(at 72.39 269.24 0)
			(effects
				(font
					(size 1.27 1.27)
					(thickness 0.15)
				)
				(justify left bottom)
				(hide yes)
			)
		)
		(property "Footprint" "antmicro-footprints:R_0402_1005Metric"
			(at 72.39 271.78 0)
			(effects
				(font
					(size 1.27 1.27)
					(thickness 0.15)
				)
				(justify left bottom)
				(hide yes)
			)
		)
		(property "Datasheet" "https://www.bourns.com/docs/product-datasheets/cr.pdf"
			(at 72.39 274.32 0)
			(effects
				(font
					(size 1.27 1.27)
					(thickness 0.15)
				)
				(justify left bottom)
				(hide yes)
			)
		)
		(property "Description" ""
			(at 52.07 256.54 0)
			(effects
				(font
					(size 1.27 1.27)
				)
			)
		)
		(property "Manufacturer" "Bourns"
			(at 72.39 279.4 0)
			(effects
				(font
					(size 1.27 1.27)
					(thickness 0.15)
				)
				(justify left bottom)
				(hide yes)
			)
		)
		(property "MPN" "CR0402-FX-2201GLF"
			(at 72.39 276.86 0)
			(effects
				(font
					(size 1.27 1.27)
					(thickness 0.15)
				)
				(justify left bottom)
				(hide yes)
			)
		)
		(property "Val" "2k2"
			(at 50.165 255.27 0)
			(effects
				(font
					(size 1.27 1.27)
					(thickness 0.15)
				)
			)
		)
		(property "DNP" "DNP"
			(at 54.61 256.54 0)
			(effects
				(font
					(size 1.27 1.27)
				)
			)
		)
		(property "License" "Apache-2.0"
			(at 72.39 281.94 0)
			(effects
				(font
					(size 1.27 1.27)
					(thickness 0.15)
				)
				(justify left bottom)
				(hide yes)
			)
		)
		(property "Author" "Antmicro"
			(at 72.39 284.48 0)
			(effects
				(font
					(size 1.27 1.27)
					(thickness 0.15)
				)
				(justify left bottom)
				(hide yes)
			)
		)
		(property "Tolerance" "1%"
			(at 72.39 266.7 0)
			(effects
				(font
					(size 1.27 1.27)
				)
				(justify left bottom)
				(hide yes)
			)
		)
		(pin "1"
		)
		(pin "2"
		)
		(instances
			(project "k410t-devboard"
				(path ""
					(reference "R227")
					(unit 1)
				)
			)
		)
	)
	(symbol
		(lib_id "antmicropower:+3.3V")
		(at 262.89 231.14 0)
		(unit 1)
		(exclude_from_sim no)
		(in_bom yes)
		(on_board yes)
		(dnp no)
		(property "Reference" "#PWR0298"
			(at 262.89 234.95 0)
			(effects
				(font
					(size 1.27 1.27)
				)
				(hide yes)
			)
		)
		(property "Value" "+3V3"
			(at 262.89 227.584 0)
			(effects
				(font
					(size 1.27 1.27)
				)
			)
		)
		(property "Footprint" ""
			(at 262.89 231.14 0)
			(effects
				(font
					(size 1.27 1.27)
				)
				(hide yes)
			)
		)
		(property "Datasheet" ""
			(at 262.89 231.14 0)
			(effects
				(font
					(size 1.27 1.27)
				)
				(hide yes)
			)
		)
		(property "Description" ""
			(at 262.89 231.14 0)
			(effects
				(font
					(size 1.27 1.27)
				)
			)
		)
		(pin "1"
		)
		(instances
			(project "k410t-devboard"
				(path ""
					(reference "#PWR0298")
					(unit 1)
				)
			)
		)
	)
	(symbol
		(lib_id "antmicroTVSDiodes:TPD4E05U06QDQARQ1")
		(at 311.15 228.6 0)
		(unit 1)
		(exclude_from_sim no)
		(in_bom yes)
		(on_board yes)
		(dnp no)
		(fields_autoplaced yes)
		(property "Reference" "U29"
			(at 321.31 231.775 0)
			(effects
				(font
					(size 1.27 1.27)
				)
				(justify left)
			)
		)
		(property "Value" "TPD4E05U06QDQARQ1"
			(at 321.945 234.3149 0)
			(effects
				(font
					(size 1.27 1.27)
					(thickness 0.15)
				)
				(justify left)
				(hide yes)
			)
		)
		(property "Footprint" "antmicro-footprints:USON-10_2.5x1mm_P0.5mm"
			(at 335.28 233.68 0)
			(effects
				(font
					(size 1.27 1.27)
					(thickness 0.15)
				)
				(justify left bottom)
				(hide yes)
			)
		)
		(property "Datasheet" "https://www.ti.com/lit/ds/symlink/tpd4e05u06-q1.pdf?HQS=dis-mous-null-mousermode-dsf-pf-null-wwe&ts=1663591265741&ref_url=https%253A%252F%252Fwww.mouser.com%252F"
			(at 335.28 236.22 0)
			(effects
				(font
					(size 1.27 1.27)
					(thickness 0.15)
				)
				(justify left bottom)
				(hide yes)
			)
		)
		(property "Description" ""
			(at 311.15 228.6 0)
			(effects
				(font
					(size 1.27 1.27)
				)
			)
		)
		(property "Manufacturer" "Texas Instruments"
			(at 335.28 238.76 0)
			(effects
				(font
					(size 1.27 1.27)
					(thickness 0.15)
				)
				(justify left bottom)
				(hide yes)
			)
		)
		(property "MPN" "TPD4E05U06QDQARQ1"
			(at 321.31 234.315 0)
			(effects
				(font
					(size 1.27 1.27)
					(thickness 0.15)
				)
				(justify left)
			)
		)
		(property "Author" "Antmicro"
			(at 335.28 243.84 0)
			(effects
				(font
					(size 1.27 1.27)
					(thickness 0.15)
				)
				(justify left bottom)
				(hide yes)
			)
		)
		(property "License" "Apache-2.0"
			(at 335.28 246.38 0)
			(effects
				(font
					(size 1.27 1.27)
					(thickness 0.15)
				)
				(justify left bottom)
				(hide yes)
			)
		)
		(pin "1"
		)
		(pin "10"
		)
		(pin "2"
		)
		(pin "3"
		)
		(pin "4"
		)
		(pin "5"
		)
		(pin "6"
		)
		(pin "7"
		)
		(pin "8"
		)
		(pin "9"
		)
		(instances
			(project "k410t-devboard"
				(path ""
					(reference "U29")
					(unit 1)
				)
			)
		)
	)
	(symbol
		(lib_id "antmicroResistors0402:R_10k_0402")
		(at 52.07 58.42 0)
		(mirror x)
		(unit 1)
		(exclude_from_sim no)
		(in_bom yes)
		(on_board yes)
		(dnp no)
		(property "Reference" "R200"
			(at 59.69 57.15 0)
			(effects
				(font
					(size 1.27 1.27)
				)
			)
		)
		(property "Value" "R_10k_0402"
			(at 72.39 45.72 0)
			(effects
				(font
					(size 1.27 1.27)
					(thickness 0.15)
				)
				(justify left bottom)
				(hide yes)
			)
		)
		(property "Footprint" "antmicro-footprints:R_0402_1005Metric"
			(at 72.39 43.18 0)
			(effects
				(font
					(size 1.27 1.27)
					(thickness 0.15)
				)
				(justify left bottom)
				(hide yes)
			)
		)
		(property "Datasheet" "https://www.bourns.com/docs/product-datasheets/cr.pdf"
			(at 72.39 40.64 0)
			(effects
				(font
					(size 1.27 1.27)
					(thickness 0.15)
				)
				(justify left bottom)
				(hide yes)
			)
		)
		(property "Description" ""
			(at 52.07 58.42 0)
			(effects
				(font
					(size 1.27 1.27)
				)
			)
		)
		(property "Manufacturer" "Bourns"
			(at 72.39 35.56 0)
			(effects
				(font
					(size 1.27 1.27)
					(thickness 0.15)
				)
				(justify left bottom)
				(hide yes)
			)
		)
		(property "MPN" "CR0402-FX-1002GLF"
			(at 72.39 38.1 0)
			(effects
				(font
					(size 1.27 1.27)
					(thickness 0.15)
				)
				(justify left bottom)
				(hide yes)
			)
		)
		(property "Val" "10k"
			(at 50.165 57.15 0)
			(effects
				(font
					(size 1.27 1.27)
					(thickness 0.15)
				)
			)
		)
		(property "License" "Apache-2.0"
			(at 72.39 33.02 0)
			(effects
				(font
					(size 1.27 1.27)
					(thickness 0.15)
				)
				(justify left bottom)
				(hide yes)
			)
		)
		(property "Author" "Antmicro"
			(at 72.39 30.48 0)
			(effects
				(font
					(size 1.27 1.27)
					(thickness 0.15)
				)
				(justify left bottom)
				(hide yes)
			)
		)
		(property "Tolerance" "1%"
			(at 72.39 48.26 0)
			(effects
				(font
					(size 1.27 1.27)
				)
				(justify left bottom)
				(hide yes)
			)
		)
		(pin "1"
		)
		(pin "2"
		)
		(instances
			(project "k410t-devboard"
				(path ""
					(reference "R200")
					(unit 1)
				)
			)
		)
	)
	(symbol
		(lib_id "antmicroCapacitors0402:C_10p_0402")
		(at 220.98 205.74 90)
		(unit 1)
		(exclude_from_sim no)
		(in_bom yes)
		(on_board yes)
		(dnp no)
		(fields_autoplaced yes)
		(property "Reference" "C275"
			(at 223.52 201.9235 90)
			(effects
				(font
					(size 1.27 1.27)
				)
				(justify right)
			)
		)
		(property "Value" "C_10p_0402"
			(at 231.14 185.42 0)
			(effects
				(font
					(size 1.27 1.27)
					(thickness 0.15)
				)
				(justify left bottom)
				(hide yes)
			)
		)
		(property "Footprint" "antmicro-footprints:C_0402_1005Metric"
			(at 233.68 185.42 0)
			(effects
				(font
					(size 1.27 1.27)
					(thickness 0.15)
				)
				(justify left bottom)
				(hide yes)
			)
		)
		(property "Datasheet" "https://www.murata.com/products/productdetail?partno=GCM1555C1H100GA16%23"
			(at 236.22 185.42 0)
			(effects
				(font
					(size 1.27 1.27)
					(thickness 0.15)
				)
				(justify left bottom)
				(hide yes)
			)
		)
		(property "Description" ""
			(at 220.98 205.74 0)
			(effects
				(font
					(size 1.27 1.27)
				)
			)
		)
		(property "Manufacturer" "Murata"
			(at 241.3 185.42 0)
			(effects
				(font
					(size 1.27 1.27)
					(thickness 0.15)
				)
				(justify left bottom)
				(hide yes)
			)
		)
		(property "MPN" "GCM1555C1H100GA16D"
			(at 238.76 185.42 0)
			(effects
				(font
					(size 1.27 1.27)
					(thickness 0.15)
				)
				(justify left bottom)
				(hide yes)
			)
		)
		(property "Val" "10p"
			(at 223.52 204.4635 90)
			(effects
				(font
					(size 1.27 1.27)
					(thickness 0.15)
				)
				(justify right)
			)
		)
		(property "License" "Apache-2.0"
			(at 243.84 185.42 0)
			(effects
				(font
					(size 1.27 1.27)
					(thickness 0.15)
				)
				(justify left bottom)
				(hide yes)
			)
		)
		(property "Author" "Antmicro"
			(at 246.38 185.42 0)
			(effects
				(font
					(size 1.27 1.27)
					(thickness 0.15)
				)
				(justify left bottom)
				(hide yes)
			)
		)
		(property "Voltage" "50V"
			(at 248.92 185.42 0)
			(effects
				(font
					(size 1.27 1.27)
				)
				(justify left bottom)
				(hide yes)
			)
		)
		(property "Dielectric" "C0G"
			(at 251.46 185.42 0)
			(effects
				(font
					(size 1.27 1.27)
				)
				(justify left bottom)
				(hide yes)
			)
		)
		(pin "1"
		)
		(pin "2"
		)
		(instances
			(project "k410t-devboard"
				(path ""
					(reference "C275")
					(unit 1)
				)
			)
		)
	)
	(symbol
		(lib_id "antmicropower:GND")
		(at 190.5 265.43 0)
		(unit 1)
		(exclude_from_sim no)
		(in_bom yes)
		(on_board yes)
		(dnp no)
		(property "Reference" "#PWR0310"
			(at 190.5 271.78 0)
			(effects
				(font
					(size 1.27 1.27)
				)
				(hide yes)
			)
		)
		(property "Value" "GND"
			(at 190.5 269.24 0)
			(effects
				(font
					(size 1.27 1.27)
				)
			)
		)
		(property "Footprint" ""
			(at 199.39 273.05 0)
			(effects
				(font
					(size 1.27 1.27)
					(thickness 0.15)
				)
				(justify left bottom)
				(hide yes)
			)
		)
		(property "Datasheet" ""
			(at 199.39 278.13 0)
			(effects
				(font
					(size 1.27 1.27)
					(thickness 0.15)
				)
				(justify left bottom)
				(hide yes)
			)
		)
		(property "Description" ""
			(at 190.5 265.43 0)
			(effects
				(font
					(size 1.27 1.27)
				)
			)
		)
		(property "Author" "Antmicro"
			(at 199.39 273.05 0)
			(effects
				(font
					(size 1.27 1.27)
					(thickness 0.15)
				)
				(justify left bottom)
				(hide yes)
			)
		)
		(property "License" "Apache-2.0"
			(at 199.39 275.59 0)
			(effects
				(font
					(size 1.27 1.27)
					(thickness 0.15)
				)
				(justify left bottom)
				(hide yes)
			)
		)
		(pin "1"
		)
		(instances
			(project "k410t-devboard"
				(path ""
					(reference "#PWR0310")
					(unit 1)
				)
			)
		)
	)
	(symbol
		(lib_id "antmicropower:GND")
		(at 195.58 182.88 0)
		(mirror y)
		(unit 1)
		(exclude_from_sim no)
		(in_bom yes)
		(on_board yes)
		(dnp no)
		(property "Reference" "#PWR0313"
			(at 195.58 189.23 0)
			(effects
				(font
					(size 1.27 1.27)
				)
				(hide yes)
			)
		)
		(property "Value" "GND"
			(at 195.58 186.69 0)
			(effects
				(font
					(size 1.27 1.27)
				)
			)
		)
		(property "Footprint" ""
			(at 186.69 190.5 0)
			(effects
				(font
					(size 1.27 1.27)
					(thickness 0.15)
				)
				(justify left bottom)
				(hide yes)
			)
		)
		(property "Datasheet" ""
			(at 186.69 195.58 0)
			(effects
				(font
					(size 1.27 1.27)
					(thickness 0.15)
				)
				(justify left bottom)
				(hide yes)
			)
		)
		(property "Description" ""
			(at 195.58 182.88 0)
			(effects
				(font
					(size 1.27 1.27)
				)
			)
		)
		(property "Author" "Antmicro"
			(at 186.69 190.5 0)
			(effects
				(font
					(size 1.27 1.27)
					(thickness 0.15)
				)
				(justify left bottom)
				(hide yes)
			)
		)
		(property "License" "Apache-2.0"
			(at 186.69 193.04 0)
			(effects
				(font
					(size 1.27 1.27)
					(thickness 0.15)
				)
				(justify left bottom)
				(hide yes)
			)
		)
		(pin "1"
		)
		(instances
			(project "k410t-devboard"
				(path ""
					(reference "#PWR0313")
					(unit 1)
				)
			)
		)
	)
	(symbol
		(lib_id "antmicroCapacitors0402:C_10u_0402")
		(at 195.58 175.26 90)
		(mirror x)
		(unit 1)
		(exclude_from_sim no)
		(in_bom yes)
		(on_board yes)
		(dnp no)
		(property "Reference" "C271"
			(at 196.215 175.895 90)
			(effects
				(font
					(size 1.27 1.27)
				)
				(justify right)
			)
		)
		(property "Value" "C_10u_0402"
			(at 205.74 195.58 0)
			(effects
				(font
					(size 1.27 1.27)
					(thickness 0.15)
				)
				(justify left bottom)
				(hide yes)
			)
		)
		(property "Footprint" "antmicro-footprints:C_0402_1005Metric"
			(at 208.28 195.58 0)
			(effects
				(font
					(size 1.27 1.27)
					(thickness 0.15)
				)
				(justify left bottom)
				(hide yes)
			)
		)
		(property "Datasheet" "https://www.yageo.com/en/Chart/Download/pdf/CC0402MRX5R5BB106"
			(at 210.82 195.58 0)
			(effects
				(font
					(size 1.27 1.27)
					(thickness 0.15)
				)
				(justify left bottom)
				(hide yes)
			)
		)
		(property "Description" ""
			(at 195.58 175.26 0)
			(effects
				(font
					(size 1.27 1.27)
				)
			)
		)
		(property "Manufacturer" "YAGEO"
			(at 215.9 195.58 0)
			(effects
				(font
					(size 1.27 1.27)
					(thickness 0.15)
				)
				(justify left bottom)
				(hide yes)
			)
		)
		(property "MPN" "CC0402MRX5R5BB106"
			(at 213.36 195.58 0)
			(effects
				(font
					(size 1.27 1.27)
					(thickness 0.15)
				)
				(justify left bottom)
				(hide yes)
			)
		)
		(property "Val" "10u"
			(at 196.215 179.705 90)
			(effects
				(font
					(size 1.27 1.27)
					(thickness 0.15)
				)
				(justify right)
			)
		)
		(property "License" "Apache-2.0"
			(at 218.44 195.58 0)
			(effects
				(font
					(size 1.27 1.27)
					(thickness 0.15)
				)
				(justify left bottom)
				(hide yes)
			)
		)
		(property "Author" "Antmicro"
			(at 220.98 195.58 0)
			(effects
				(font
					(size 1.27 1.27)
					(thickness 0.15)
				)
				(justify left bottom)
				(hide yes)
			)
		)
		(property "Voltage" ""
			(at 223.52 195.58 0)
			(effects
				(font
					(size 1.27 1.27)
				)
				(justify left bottom)
				(hide yes)
			)
		)
		(property "Dielectric" ""
			(at 226.06 195.58 0)
			(effects
				(font
					(size 1.27 1.27)
				)
				(justify left bottom)
				(hide yes)
			)
		)
		(pin "1"
		)
		(pin "2"
		)
		(instances
			(project "k410t-devboard"
				(path ""
					(reference "C271")
					(unit 1)
				)
			)
		)
	)
	(symbol
		(lib_id "antmicroResistors0402:R_2k2_0402")
		(at 52.07 105.41 0)
		(unit 1)
		(exclude_from_sim no)
		(in_bom no)
		(on_board yes)
		(dnp yes)
		(property "Reference" "R215"
			(at 59.69 104.14 0)
			(effects
				(font
					(size 1.27 1.27)
				)
			)
		)
		(property "Value" "R_2k2_0402"
			(at 72.39 118.11 0)
			(effects
				(font
					(size 1.27 1.27)
					(thickness 0.15)
				)
				(justify left bottom)
				(hide yes)
			)
		)
		(property "Footprint" "antmicro-footprints:R_0402_1005Metric"
			(at 72.39 120.65 0)
			(effects
				(font
					(size 1.27 1.27)
					(thickness 0.15)
				)
				(justify left bottom)
				(hide yes)
			)
		)
		(property "Datasheet" "https://www.bourns.com/docs/product-datasheets/cr.pdf"
			(at 72.39 123.19 0)
			(effects
				(font
					(size 1.27 1.27)
					(thickness 0.15)
				)
				(justify left bottom)
				(hide yes)
			)
		)
		(property "Description" ""
			(at 52.07 105.41 0)
			(effects
				(font
					(size 1.27 1.27)
				)
			)
		)
		(property "Manufacturer" "Bourns"
			(at 72.39 128.27 0)
			(effects
				(font
					(size 1.27 1.27)
					(thickness 0.15)
				)
				(justify left bottom)
				(hide yes)
			)
		)
		(property "MPN" "CR0402-FX-2201GLF"
			(at 72.39 125.73 0)
			(effects
				(font
					(size 1.27 1.27)
					(thickness 0.15)
				)
				(justify left bottom)
				(hide yes)
			)
		)
		(property "Val" "2k2"
			(at 50.165 104.14 0)
			(effects
				(font
					(size 1.27 1.27)
					(thickness 0.15)
				)
			)
		)
		(property "DNP" "DNP"
			(at 54.61 105.41 0)
			(effects
				(font
					(size 1.27 1.27)
				)
			)
		)
		(property "License" "Apache-2.0"
			(at 72.39 130.81 0)
			(effects
				(font
					(size 1.27 1.27)
					(thickness 0.15)
				)
				(justify left bottom)
				(hide yes)
			)
		)
		(property "Author" "Antmicro"
			(at 72.39 133.35 0)
			(effects
				(font
					(size 1.27 1.27)
					(thickness 0.15)
				)
				(justify left bottom)
				(hide yes)
			)
		)
		(property "Tolerance" "1%"
			(at 72.39 115.57 0)
			(effects
				(font
					(size 1.27 1.27)
				)
				(justify left bottom)
				(hide yes)
			)
		)
		(pin "1"
		)
		(pin "2"
		)
		(instances
			(project "k410t-devboard"
				(path ""
					(reference "R215")
					(unit 1)
				)
			)
		)
	)
	(symbol
		(lib_id "antmicroCapacitors0402:C_22p_0402")
		(at 124.46 129.54 90)
		(unit 1)
		(exclude_from_sim no)
		(in_bom yes)
		(on_board yes)
		(dnp no)
		(property "Reference" "C256"
			(at 123.825 125.095 90)
			(effects
				(font
					(size 1.27 1.27)
				)
				(justify left)
			)
		)
		(property "Value" "C_22p_0402"
			(at 134.62 109.22 0)
			(effects
				(font
					(size 1.27 1.27)
					(thickness 0.15)
				)
				(justify left bottom)
				(hide yes)
			)
		)
		(property "Footprint" "antmicro-footprints:C_0402_1005Metric"
			(at 137.16 109.22 0)
			(effects
				(font
					(size 1.27 1.27)
					(thickness 0.15)
				)
				(justify left bottom)
				(hide yes)
			)
		)
		(property "Datasheet" "https://www.yageo.com/en/Chart/Download/pdf/CC0402JRNPO9BN220"
			(at 139.7 109.22 0)
			(effects
				(font
					(size 1.27 1.27)
					(thickness 0.15)
				)
				(justify left bottom)
				(hide yes)
			)
		)
		(property "Description" ""
			(at 124.46 129.54 0)
			(effects
				(font
					(size 1.27 1.27)
				)
			)
		)
		(property "Manufacturer" "YAGEO"
			(at 144.78 109.22 0)
			(effects
				(font
					(size 1.27 1.27)
					(thickness 0.15)
				)
				(justify left bottom)
				(hide yes)
			)
		)
		(property "MPN" "CC0402JRNPO9BN220"
			(at 142.24 109.22 0)
			(effects
				(font
					(size 1.27 1.27)
					(thickness 0.15)
				)
				(justify left bottom)
				(hide yes)
			)
		)
		(property "Val" "22p"
			(at 123.825 128.905 90)
			(effects
				(font
					(size 1.27 1.27)
					(thickness 0.15)
				)
				(justify left)
			)
		)
		(property "License" "Apache-2.0"
			(at 147.32 109.22 0)
			(effects
				(font
					(size 1.27 1.27)
					(thickness 0.15)
				)
				(justify left bottom)
				(hide yes)
			)
		)
		(property "Author" "Antmicro"
			(at 149.86 109.22 0)
			(effects
				(font
					(size 1.27 1.27)
					(thickness 0.15)
				)
				(justify left bottom)
				(hide yes)
			)
		)
		(property "Voltage" ""
			(at 152.4 109.22 0)
			(effects
				(font
					(size 1.27 1.27)
				)
				(justify left bottom)
				(hide yes)
			)
		)
		(property "Dielectric" ""
			(at 154.94 109.22 0)
			(effects
				(font
					(size 1.27 1.27)
				)
				(justify left bottom)
				(hide yes)
			)
		)
		(pin "1"
		)
		(pin "2"
		)
		(instances
			(project "k410t-devboard"
				(path ""
					(reference "C256")
					(unit 1)
				)
			)
		)
	)
	(symbol
		(lib_id "antmicroResistors0402:R_2k2_0402")
		(at 52.07 93.98 0)
		(unit 1)
		(exclude_from_sim no)
		(in_bom yes)
		(on_board yes)
		(dnp no)
		(property "Reference" "R211"
			(at 59.69 92.71 0)
			(effects
				(font
					(size 1.27 1.27)
				)
			)
		)
		(property "Value" "R_2k2_0402"
			(at 72.39 106.68 0)
			(effects
				(font
					(size 1.27 1.27)
					(thickness 0.15)
				)
				(justify left bottom)
				(hide yes)
			)
		)
		(property "Footprint" "antmicro-footprints:R_0402_1005Metric"
			(at 72.39 109.22 0)
			(effects
				(font
					(size 1.27 1.27)
					(thickness 0.15)
				)
				(justify left bottom)
				(hide yes)
			)
		)
		(property "Datasheet" "https://www.bourns.com/docs/product-datasheets/cr.pdf"
			(at 72.39 111.76 0)
			(effects
				(font
					(size 1.27 1.27)
					(thickness 0.15)
				)
				(justify left bottom)
				(hide yes)
			)
		)
		(property "Description" ""
			(at 52.07 93.98 0)
			(effects
				(font
					(size 1.27 1.27)
				)
			)
		)
		(property "Manufacturer" "Bourns"
			(at 72.39 116.84 0)
			(effects
				(font
					(size 1.27 1.27)
					(thickness 0.15)
				)
				(justify left bottom)
				(hide yes)
			)
		)
		(property "MPN" "CR0402-FX-2201GLF"
			(at 72.39 114.3 0)
			(effects
				(font
					(size 1.27 1.27)
					(thickness 0.15)
				)
				(justify left bottom)
				(hide yes)
			)
		)
		(property "Val" "2k2"
			(at 50.165 92.71 0)
			(effects
				(font
					(size 1.27 1.27)
					(thickness 0.15)
				)
			)
		)
		(property "License" "Apache-2.0"
			(at 72.39 119.38 0)
			(effects
				(font
					(size 1.27 1.27)
					(thickness 0.15)
				)
				(justify left bottom)
				(hide yes)
			)
		)
		(property "Author" "Antmicro"
			(at 72.39 121.92 0)
			(effects
				(font
					(size 1.27 1.27)
					(thickness 0.15)
				)
				(justify left bottom)
				(hide yes)
			)
		)
		(property "Tolerance" "1%"
			(at 72.39 104.14 0)
			(effects
				(font
					(size 1.27 1.27)
				)
				(justify left bottom)
				(hide yes)
			)
		)
		(pin "1"
		)
		(pin "2"
		)
		(instances
			(project "k410t-devboard"
				(path ""
					(reference "R211")
					(unit 1)
				)
			)
		)
	)
	(symbol
		(lib_id "antmicroCapacitors0402:C_100n_0402")
		(at 280.67 26.67 90)
		(unit 1)
		(exclude_from_sim no)
		(in_bom yes)
		(on_board yes)
		(dnp no)
		(property "Reference" "C288"
			(at 281.305 22.225 90)
			(effects
				(font
					(size 1.27 1.27)
				)
				(justify right)
			)
		)
		(property "Value" "C_100n_0402"
			(at 290.83 6.35 0)
			(effects
				(font
					(size 1.27 1.27)
					(thickness 0.15)
				)
				(justify left bottom)
				(hide yes)
			)
		)
		(property "Footprint" "antmicro-footprints:C_0402_1005Metric"
			(at 293.37 6.35 0)
			(effects
				(font
					(size 1.27 1.27)
					(thickness 0.15)
				)
				(justify left bottom)
				(hide yes)
			)
		)
		(property "Datasheet" "https://www.murata.com/products/productdetail?partno=GRM155R61H104KE14%23"
			(at 295.91 6.35 0)
			(effects
				(font
					(size 1.27 1.27)
					(thickness 0.15)
				)
				(justify left bottom)
				(hide yes)
			)
		)
		(property "Description" ""
			(at 280.67 26.67 0)
			(effects
				(font
					(size 1.27 1.27)
				)
			)
		)
		(property "Manufacturer" "Murata"
			(at 300.99 6.35 0)
			(effects
				(font
					(size 1.27 1.27)
					(thickness 0.15)
				)
				(justify left bottom)
				(hide yes)
			)
		)
		(property "MPN" "GRM155R61H104KE14D"
			(at 298.45 6.35 0)
			(effects
				(font
					(size 1.27 1.27)
					(thickness 0.15)
				)
				(justify left bottom)
				(hide yes)
			)
		)
		(property "Val" "100n"
			(at 281.305 26.035 90)
			(effects
				(font
					(size 1.27 1.27)
					(thickness 0.15)
				)
				(justify right)
			)
		)
		(property "License" "Apache-2.0"
			(at 303.53 6.35 0)
			(effects
				(font
					(size 1.27 1.27)
					(thickness 0.15)
				)
				(justify left bottom)
				(hide yes)
			)
		)
		(property "Author" "Antmicro"
			(at 306.07 6.35 0)
			(effects
				(font
					(size 1.27 1.27)
					(thickness 0.15)
				)
				(justify left bottom)
				(hide yes)
			)
		)
		(property "Voltage" "50V"
			(at 308.61 6.35 0)
			(effects
				(font
					(size 1.27 1.27)
				)
				(justify left bottom)
				(hide yes)
			)
		)
		(property "Dielectric" "X5R"
			(at 311.15 6.35 0)
			(effects
				(font
					(size 1.27 1.27)
				)
				(justify left bottom)
				(hide yes)
			)
		)
		(pin "1"
		)
		(pin "2"
		)
		(instances
			(project "k410t-devboard"
				(path ""
					(reference "C288")
					(unit 1)
				)
			)
		)
	)
	(symbol
		(lib_id "antmicropower:+1V8")
		(at 21.59 171.45 0)
		(unit 1)
		(exclude_from_sim no)
		(in_bom yes)
		(on_board yes)
		(dnp no)
		(property "Reference" "#PWR0251"
			(at 21.59 175.26 0)
			(effects
				(font
					(size 1.27 1.27)
				)
				(hide yes)
			)
		)
		(property "Value" "+1V8"
			(at 21.59 167.894 0)
			(effects
				(font
					(size 1.27 1.27)
				)
			)
		)
		(property "Footprint" ""
			(at 36.83 179.07 0)
			(effects
				(font
					(size 1.27 1.27)
					(thickness 0.15)
				)
				(justify left bottom)
				(hide yes)
			)
		)
		(property "Datasheet" ""
			(at 36.83 181.61 0)
			(effects
				(font
					(size 1.27 1.27)
					(thickness 0.15)
				)
				(justify left bottom)
				(hide yes)
			)
		)
		(property "Description" ""
			(at 21.59 171.45 0)
			(effects
				(font
					(size 1.27 1.27)
				)
			)
		)
		(property "Author" "Antmicro"
			(at 36.83 179.07 0)
			(effects
				(font
					(size 1.27 1.27)
					(thickness 0.15)
				)
				(justify left bottom)
				(hide yes)
			)
		)
		(property "License" "Apache-2.0"
			(at 36.83 181.61 0)
			(effects
				(font
					(size 1.27 1.27)
					(thickness 0.15)
				)
				(justify left bottom)
				(hide yes)
			)
		)
		(pin "1"
		)
		(instances
			(project "k410t-devboard"
				(path ""
					(reference "#PWR0251")
					(unit 1)
				)
			)
		)
	)
	(symbol
		(lib_id "antmicropower:+1V2")
		(at 332.74 19.05 0)
		(unit 1)
		(exclude_from_sim no)
		(in_bom yes)
		(on_board yes)
		(dnp no)
		(fields_autoplaced yes)
		(property "Reference" "#PWR0312"
			(at 332.74 22.86 0)
			(effects
				(font
					(size 1.27 1.27)
				)
				(hide yes)
			)
		)
		(property "Value" "+1V2"
			(at 332.74 15.494 0)
			(effects
				(font
					(size 1.27 1.27)
				)
			)
		)
		(property "Footprint" ""
			(at 332.74 19.05 0)
			(effects
				(font
					(size 1.27 1.27)
				)
				(hide yes)
			)
		)
		(property "Datasheet" ""
			(at 332.74 19.05 0)
			(effects
				(font
					(size 1.27 1.27)
				)
				(hide yes)
			)
		)
		(property "Description" ""
			(at 332.74 19.05 0)
			(effects
				(font
					(size 1.27 1.27)
				)
			)
		)
		(pin "1"
		)
		(instances
			(project "k410t-devboard"
				(path ""
					(reference "#PWR0312")
					(unit 1)
				)
			)
		)
	)
	(symbol
		(lib_id "antmicropower:+3.3V")
		(at 111.76 53.34 0)
		(unit 1)
		(exclude_from_sim no)
		(in_bom yes)
		(on_board yes)
		(dnp no)
		(fields_autoplaced yes)
		(property "Reference" "#PWR0259"
			(at 111.76 57.15 0)
			(effects
				(font
					(size 1.27 1.27)
				)
				(hide yes)
			)
		)
		(property "Value" "+3V3"
			(at 111.76 49.784 0)
			(effects
				(font
					(size 1.27 1.27)
				)
			)
		)
		(property "Footprint" ""
			(at 111.76 53.34 0)
			(effects
				(font
					(size 1.27 1.27)
				)
				(hide yes)
			)
		)
		(property "Datasheet" ""
			(at 111.76 53.34 0)
			(effects
				(font
					(size 1.27 1.27)
				)
				(hide yes)
			)
		)
		(property "Description" ""
			(at 111.76 53.34 0)
			(effects
				(font
					(size 1.27 1.27)
				)
			)
		)
		(pin "1"
		)
		(instances
			(project "k410t-devboard"
				(path ""
					(reference "#PWR0259")
					(unit 1)
				)
			)
		)
	)
	(symbol
		(lib_id "antmicropower:GND")
		(at 184.15 222.25 0)
		(unit 1)
		(exclude_from_sim no)
		(in_bom yes)
		(on_board yes)
		(dnp no)
		(property "Reference" "#PWR0309"
			(at 184.15 228.6 0)
			(effects
				(font
					(size 1.27 1.27)
				)
				(hide yes)
			)
		)
		(property "Value" "GND"
			(at 184.15 226.06 0)
			(effects
				(font
					(size 1.27 1.27)
				)
			)
		)
		(property "Footprint" ""
			(at 193.04 229.87 0)
			(effects
				(font
					(size 1.27 1.27)
					(thickness 0.15)
				)
				(justify left bottom)
				(hide yes)
			)
		)
		(property "Datasheet" ""
			(at 193.04 234.95 0)
			(effects
				(font
					(size 1.27 1.27)
					(thickness 0.15)
				)
				(justify left bottom)
				(hide yes)
			)
		)
		(property "Description" ""
			(at 184.15 222.25 0)
			(effects
				(font
					(size 1.27 1.27)
				)
			)
		)
		(property "Author" "Antmicro"
			(at 193.04 229.87 0)
			(effects
				(font
					(size 1.27 1.27)
					(thickness 0.15)
				)
				(justify left bottom)
				(hide yes)
			)
		)
		(property "License" "Apache-2.0"
			(at 193.04 232.41 0)
			(effects
				(font
					(size 1.27 1.27)
					(thickness 0.15)
				)
				(justify left bottom)
				(hide yes)
			)
		)
		(pin "1"
		)
		(instances
			(project "k410t-devboard"
				(path ""
					(reference "#PWR0309")
					(unit 1)
				)
			)
		)
	)
	(symbol
		(lib_id "antmicropower:GND")
		(at 129.54 241.3 0)
		(unit 1)
		(exclude_from_sim no)
		(in_bom yes)
		(on_board yes)
		(dnp no)
		(property "Reference" "#PWR0293"
			(at 129.54 247.65 0)
			(effects
				(font
					(size 1.27 1.27)
				)
				(hide yes)
			)
		)
		(property "Value" "GND"
			(at 129.54 245.11 0)
			(effects
				(font
					(size 1.27 1.27)
				)
			)
		)
		(property "Footprint" ""
			(at 138.43 248.92 0)
			(effects
				(font
					(size 1.27 1.27)
					(thickness 0.15)
				)
				(justify left bottom)
				(hide yes)
			)
		)
		(property "Datasheet" ""
			(at 138.43 254 0)
			(effects
				(font
					(size 1.27 1.27)
					(thickness 0.15)
				)
				(justify left bottom)
				(hide yes)
			)
		)
		(property "Description" ""
			(at 129.54 241.3 0)
			(effects
				(font
					(size 1.27 1.27)
				)
			)
		)
		(property "Author" "Antmicro"
			(at 138.43 248.92 0)
			(effects
				(font
					(size 1.27 1.27)
					(thickness 0.15)
				)
				(justify left bottom)
				(hide yes)
			)
		)
		(property "License" "Apache-2.0"
			(at 138.43 251.46 0)
			(effects
				(font
					(size 1.27 1.27)
					(thickness 0.15)
				)
				(justify left bottom)
				(hide yes)
			)
		)
		(pin "1"
		)
		(instances
			(project "k410t-devboard"
				(path ""
					(reference "#PWR0293")
					(unit 1)
				)
			)
		)
	)
	(symbol
		(lib_id "antmicroCapacitors0402:C_10u_0402")
		(at 317.5 43.18 90)
		(unit 1)
		(exclude_from_sim no)
		(in_bom yes)
		(on_board yes)
		(dnp no)
		(property "Reference" "C293"
			(at 318.135 38.735 90)
			(effects
				(font
					(size 1.27 1.27)
				)
				(justify right)
			)
		)
		(property "Value" "C_10u_0402"
			(at 327.66 22.86 0)
			(effects
				(font
					(size 1.27 1.27)
					(thickness 0.15)
				)
				(justify left bottom)
				(hide yes)
			)
		)
		(property "Footprint" "antmicro-footprints:C_0402_1005Metric"
			(at 330.2 22.86 0)
			(effects
				(font
					(size 1.27 1.27)
					(thickness 0.15)
				)
				(justify left bottom)
				(hide yes)
			)
		)
		(property "Datasheet" "https://www.yageo.com/en/Chart/Download/pdf/CC0402MRX5R5BB106"
			(at 332.74 22.86 0)
			(effects
				(font
					(size 1.27 1.27)
					(thickness 0.15)
				)
				(justify left bottom)
				(hide yes)
			)
		)
		(property "Description" ""
			(at 317.5 43.18 0)
			(effects
				(font
					(size 1.27 1.27)
				)
			)
		)
		(property "Manufacturer" "YAGEO"
			(at 337.82 22.86 0)
			(effects
				(font
					(size 1.27 1.27)
					(thickness 0.15)
				)
				(justify left bottom)
				(hide yes)
			)
		)
		(property "MPN" "CC0402MRX5R5BB106"
			(at 335.28 22.86 0)
			(effects
				(font
					(size 1.27 1.27)
					(thickness 0.15)
				)
				(justify left bottom)
				(hide yes)
			)
		)
		(property "Val" "10u"
			(at 318.135 42.545 90)
			(effects
				(font
					(size 1.27 1.27)
					(thickness 0.15)
				)
				(justify right)
			)
		)
		(property "License" "Apache-2.0"
			(at 340.36 22.86 0)
			(effects
				(font
					(size 1.27 1.27)
					(thickness 0.15)
				)
				(justify left bottom)
				(hide yes)
			)
		)
		(property "Author" "Antmicro"
			(at 342.9 22.86 0)
			(effects
				(font
					(size 1.27 1.27)
					(thickness 0.15)
				)
				(justify left bottom)
				(hide yes)
			)
		)
		(property "Voltage" ""
			(at 345.44 22.86 0)
			(effects
				(font
					(size 1.27 1.27)
				)
				(justify left bottom)
				(hide yes)
			)
		)
		(property "Dielectric" ""
			(at 347.98 22.86 0)
			(effects
				(font
					(size 1.27 1.27)
				)
				(justify left bottom)
				(hide yes)
			)
		)
		(pin "1"
		)
		(pin "2"
		)
		(instances
			(project "k410t-devboard"
				(path ""
					(reference "C293")
					(unit 1)
				)
			)
		)
	)
	(symbol
		(lib_id "antmicroResistors0402:R_0R_0402")
		(at 190.5 252.73 90)
		(unit 1)
		(exclude_from_sim no)
		(in_bom yes)
		(on_board yes)
		(dnp no)
		(fields_autoplaced yes)
		(property "Reference" "R243"
			(at 193.04 248.9199 90)
			(effects
				(font
					(size 1.27 1.27)
				)
				(justify right)
			)
		)
		(property "Value" "R_0R_0402"
			(at 203.2 232.41 0)
			(effects
				(font
					(size 1.27 1.27)
					(thickness 0.15)
				)
				(justify left bottom)
				(hide yes)
			)
		)
		(property "Footprint" "antmicro-footprints:R_0402_1005Metric"
			(at 205.74 232.41 0)
			(effects
				(font
					(size 1.27 1.27)
					(thickness 0.15)
				)
				(justify left bottom)
				(hide yes)
			)
		)
		(property "Datasheet" "https://industrial.panasonic.com/cdbs/www-data/pdf/RDA0000/AOA0000C301.pdf"
			(at 208.28 232.41 0)
			(effects
				(font
					(size 1.27 1.27)
					(thickness 0.15)
				)
				(justify left bottom)
				(hide yes)
			)
		)
		(property "Description" ""
			(at 190.5 252.73 0)
			(effects
				(font
					(size 1.27 1.27)
				)
			)
		)
		(property "Manufacturer" "Panasonic"
			(at 213.36 232.41 0)
			(effects
				(font
					(size 1.27 1.27)
					(thickness 0.15)
				)
				(justify left bottom)
				(hide yes)
			)
		)
		(property "MPN" "ERJ2GE0R00X"
			(at 210.82 232.41 0)
			(effects
				(font
					(size 1.27 1.27)
					(thickness 0.15)
				)
				(justify left bottom)
				(hide yes)
			)
		)
		(property "Val" "0R"
			(at 193.04 251.4599 90)
			(effects
				(font
					(size 1.27 1.27)
					(thickness 0.15)
				)
				(justify right)
			)
		)
		(property "License" "Apache-2.0"
			(at 215.9 232.41 0)
			(effects
				(font
					(size 1.27 1.27)
					(thickness 0.15)
				)
				(justify left bottom)
				(hide yes)
			)
		)
		(property "Author" "Antmicro"
			(at 218.44 232.41 0)
			(effects
				(font
					(size 1.27 1.27)
					(thickness 0.15)
				)
				(justify left bottom)
				(hide yes)
			)
		)
		(property "Tolerance" "~"
			(at 200.66 232.41 0)
			(effects
				(font
					(size 1.27 1.27)
				)
				(justify left bottom)
				(hide yes)
			)
		)
		(property "Current" "1A"
			(at 193.04 252.7299 90)
			(effects
				(font
					(size 1.27 1.27)
					(thickness 0.15)
				)
				(justify right)
				(hide yes)
			)
		)
		(pin "1"
		)
		(pin "2"
		)
		(instances
			(project "k410t-devboard"
				(path ""
					(reference "R243")
					(unit 1)
				)
			)
		)
	)
	(symbol
		(lib_id "antmicroFerriteBeadsandChips:FB_120Z_2A_Murata-BLM18PG_0603")
		(at 114.3 24.13 90)
		(mirror x)
		(unit 1)
		(exclude_from_sim no)
		(in_bom yes)
		(on_board yes)
		(dnp no)
		(fields_autoplaced yes)
		(property "Reference" "FB7"
			(at 111.76 25.3619 90)
			(effects
				(font
					(size 1.27 1.27)
				)
				(justify left)
			)
		)
		(property "Value" "FB_120Z_2A_Murata-BLM18PG_0603"
			(at 111.125 27.9018 90)
			(effects
				(font
					(size 1.27 1.27)
					(thickness 0.15)
				)
				(justify left)
				(hide yes)
			)
		)
		(property "Footprint" "antmicro-footprints:FB_0603_1608Metric"
			(at 119.38 38.1 0)
			(effects
				(font
					(size 1.27 1.27)
					(thickness 0.15)
				)
				(justify left bottom)
				(hide yes)
			)
		)
		(property "Datasheet" "https://www.murata.com/en-us/products/productdata/8796738650142/ENFA0003.pdf"
			(at 121.92 38.1 0)
			(effects
				(font
					(size 1.27 1.27)
					(thickness 0.15)
				)
				(justify left bottom)
				(hide yes)
			)
		)
		(property "Description" ""
			(at 114.3 24.13 0)
			(effects
				(font
					(size 1.27 1.27)
				)
			)
		)
		(property "MPN" "BLM18PG121SN1D"
			(at 124.46 38.1 0)
			(effects
				(font
					(size 1.27 1.27)
					(thickness 0.15)
				)
				(justify left bottom)
				(hide yes)
			)
		)
		(property "Manufacturer" "Murata"
			(at 127 38.1 0)
			(effects
				(font
					(size 1.27 1.27)
					(thickness 0.15)
				)
				(justify left bottom)
				(hide yes)
			)
		)
		(property "Author" "Antmicro"
			(at 129.54 38.1 0)
			(effects
				(font
					(size 1.27 1.27)
					(thickness 0.15)
				)
				(justify left bottom)
				(hide yes)
			)
		)
		(property "License" "Apache-2.0"
			(at 132.08 38.1 0)
			(effects
				(font
					(size 1.27 1.27)
					(thickness 0.15)
				)
				(justify left bottom)
				(hide yes)
			)
		)
		(property "Val" "120Z/2A"
			(at 111.76 27.9019 90)
			(effects
				(font
					(size 1.27 1.27)
				)
				(justify left)
			)
		)
		(property "Current" ""
			(at 137.16 44.45 0)
			(effects
				(font
					(size 1.27 1.27)
					(thickness 0.15)
				)
				(justify left bottom)
				(hide yes)
			)
		)
		(pin "1"
		)
		(pin "2"
		)
		(instances
			(project "k410t-devboard"
				(path ""
					(reference "FB7")
					(unit 1)
				)
			)
		)
	)
	(symbol
		(lib_id "antmicropower:+3.3V")
		(at 68.58 52.07 0)
		(unit 1)
		(exclude_from_sim no)
		(in_bom yes)
		(on_board yes)
		(dnp no)
		(fields_autoplaced yes)
		(property "Reference" "#PWR0252"
			(at 68.58 55.88 0)
			(effects
				(font
					(size 1.27 1.27)
				)
				(hide yes)
			)
		)
		(property "Value" "+3V3"
			(at 68.58 48.514 0)
			(effects
				(font
					(size 1.27 1.27)
				)
			)
		)
		(property "Footprint" ""
			(at 68.58 52.07 0)
			(effects
				(font
					(size 1.27 1.27)
				)
				(hide yes)
			)
		)
		(property "Datasheet" ""
			(at 68.58 52.07 0)
			(effects
				(font
					(size 1.27 1.27)
				)
				(hide yes)
			)
		)
		(property "Description" ""
			(at 68.58 52.07 0)
			(effects
				(font
					(size 1.27 1.27)
				)
			)
		)
		(pin "1"
		)
		(instances
			(project "k410t-devboard"
				(path ""
					(reference "#PWR0252")
					(unit 1)
				)
			)
		)
	)
	(symbol
		(lib_id "antmicroResistors0402:R_2k2_0402")
		(at 52.07 251.46 0)
		(unit 1)
		(exclude_from_sim no)
		(in_bom no)
		(on_board yes)
		(dnp yes)
		(property "Reference" "R225"
			(at 59.69 250.19 0)
			(effects
				(font
					(size 1.27 1.27)
				)
			)
		)
		(property "Value" "R_2k2_0402"
			(at 72.39 264.16 0)
			(effects
				(font
					(size 1.27 1.27)
					(thickness 0.15)
				)
				(justify left bottom)
				(hide yes)
			)
		)
		(property "Footprint" "antmicro-footprints:R_0402_1005Metric"
			(at 72.39 266.7 0)
			(effects
				(font
					(size 1.27 1.27)
					(thickness 0.15)
				)
				(justify left bottom)
				(hide yes)
			)
		)
		(property "Datasheet" "https://www.bourns.com/docs/product-datasheets/cr.pdf"
			(at 72.39 269.24 0)
			(effects
				(font
					(size 1.27 1.27)
					(thickness 0.15)
				)
				(justify left bottom)
				(hide yes)
			)
		)
		(property "Description" ""
			(at 52.07 251.46 0)
			(effects
				(font
					(size 1.27 1.27)
				)
			)
		)
		(property "Manufacturer" "Bourns"
			(at 72.39 274.32 0)
			(effects
				(font
					(size 1.27 1.27)
					(thickness 0.15)
				)
				(justify left bottom)
				(hide yes)
			)
		)
		(property "MPN" "CR0402-FX-2201GLF"
			(at 72.39 271.78 0)
			(effects
				(font
					(size 1.27 1.27)
					(thickness 0.15)
				)
				(justify left bottom)
				(hide yes)
			)
		)
		(property "Val" "2k2"
			(at 50.165 250.19 0)
			(effects
				(font
					(size 1.27 1.27)
					(thickness 0.15)
				)
			)
		)
		(property "DNP" "DNP"
			(at 54.61 251.46 0)
			(effects
				(font
					(size 1.27 1.27)
				)
			)
		)
		(property "License" "Apache-2.0"
			(at 72.39 276.86 0)
			(effects
				(font
					(size 1.27 1.27)
					(thickness 0.15)
				)
				(justify left bottom)
				(hide yes)
			)
		)
		(property "Author" "Antmicro"
			(at 72.39 279.4 0)
			(effects
				(font
					(size 1.27 1.27)
					(thickness 0.15)
				)
				(justify left bottom)
				(hide yes)
			)
		)
		(property "Tolerance" "1%"
			(at 72.39 261.62 0)
			(effects
				(font
					(size 1.27 1.27)
				)
				(justify left bottom)
				(hide yes)
			)
		)
		(pin "1"
		)
		(pin "2"
		)
		(instances
			(project "k410t-devboard"
				(path ""
					(reference "R225")
					(unit 1)
				)
			)
		)
	)
	(symbol
		(lib_id "antmicropower:+1V8")
		(at 110.49 153.67 0)
		(unit 1)
		(exclude_from_sim no)
		(in_bom yes)
		(on_board yes)
		(dnp no)
		(property "Reference" "#PWR0258"
			(at 110.49 157.48 0)
			(effects
				(font
					(size 1.27 1.27)
				)
				(hide yes)
			)
		)
		(property "Value" "+1V8"
			(at 110.49 150.114 0)
			(effects
				(font
					(size 1.27 1.27)
				)
			)
		)
		(property "Footprint" ""
			(at 125.73 161.29 0)
			(effects
				(font
					(size 1.27 1.27)
					(thickness 0.15)
				)
				(justify left bottom)
				(hide yes)
			)
		)
		(property "Datasheet" ""
			(at 125.73 163.83 0)
			(effects
				(font
					(size 1.27 1.27)
					(thickness 0.15)
				)
				(justify left bottom)
				(hide yes)
			)
		)
		(property "Description" ""
			(at 110.49 153.67 0)
			(effects
				(font
					(size 1.27 1.27)
				)
			)
		)
		(property "Author" "Antmicro"
			(at 125.73 161.29 0)
			(effects
				(font
					(size 1.27 1.27)
					(thickness 0.15)
				)
				(justify left bottom)
				(hide yes)
			)
		)
		(property "License" "Apache-2.0"
			(at 125.73 163.83 0)
			(effects
				(font
					(size 1.27 1.27)
					(thickness 0.15)
				)
				(justify left bottom)
				(hide yes)
			)
		)
		(pin "1"
		)
		(instances
			(project "k410t-devboard"
				(path ""
					(reference "#PWR0258")
					(unit 1)
				)
			)
		)
	)
	(symbol
		(lib_id "antmicropower:GND")
		(at 184.15 163.83 0)
		(mirror y)
		(unit 1)
		(exclude_from_sim no)
		(in_bom yes)
		(on_board yes)
		(dnp no)
		(property "Reference" "#PWR0307"
			(at 184.15 170.18 0)
			(effects
				(font
					(size 1.27 1.27)
				)
				(hide yes)
			)
		)
		(property "Value" "GND"
			(at 184.15 167.64 0)
			(effects
				(font
					(size 1.27 1.27)
				)
			)
		)
		(property "Footprint" ""
			(at 175.26 171.45 0)
			(effects
				(font
					(size 1.27 1.27)
					(thickness 0.15)
				)
				(justify left bottom)
				(hide yes)
			)
		)
		(property "Datasheet" ""
			(at 175.26 176.53 0)
			(effects
				(font
					(size 1.27 1.27)
					(thickness 0.15)
				)
				(justify left bottom)
				(hide yes)
			)
		)
		(property "Description" ""
			(at 184.15 163.83 0)
			(effects
				(font
					(size 1.27 1.27)
				)
			)
		)
		(property "Author" "Antmicro"
			(at 175.26 171.45 0)
			(effects
				(font
					(size 1.27 1.27)
					(thickness 0.15)
				)
				(justify left bottom)
				(hide yes)
			)
		)
		(property "License" "Apache-2.0"
			(at 175.26 173.99 0)
			(effects
				(font
					(size 1.27 1.27)
					(thickness 0.15)
				)
				(justify left bottom)
				(hide yes)
			)
		)
		(pin "1"
		)
		(instances
			(project "k410t-devboard"
				(path ""
					(reference "#PWR0307")
					(unit 1)
				)
			)
		)
	)
	(symbol
		(lib_id "antmicropower:GND")
		(at 259.08 29.21 0)
		(mirror y)
		(unit 1)
		(exclude_from_sim no)
		(in_bom yes)
		(on_board yes)
		(dnp no)
		(fields_autoplaced yes)
		(property "Reference" "#PWR0327"
			(at 259.08 35.56 0)
			(effects
				(font
					(size 1.27 1.27)
				)
				(hide yes)
			)
		)
		(property "Value" "GND"
			(at 259.08 33.02 0)
			(effects
				(font
					(size 1.27 1.27)
				)
			)
		)
		(property "Footprint" ""
			(at 250.19 36.83 0)
			(effects
				(font
					(size 1.27 1.27)
					(thickness 0.15)
				)
				(justify left bottom)
				(hide yes)
			)
		)
		(property "Datasheet" ""
			(at 250.19 41.91 0)
			(effects
				(font
					(size 1.27 1.27)
					(thickness 0.15)
				)
				(justify left bottom)
				(hide yes)
			)
		)
		(property "Description" ""
			(at 259.08 29.21 0)
			(effects
				(font
					(size 1.27 1.27)
				)
			)
		)
		(property "Author" "Antmicro"
			(at 250.19 36.83 0)
			(effects
				(font
					(size 1.27 1.27)
					(thickness 0.15)
				)
				(justify left bottom)
				(hide yes)
			)
		)
		(property "License" "Apache-2.0"
			(at 250.19 39.37 0)
			(effects
				(font
					(size 1.27 1.27)
					(thickness 0.15)
				)
				(justify left bottom)
				(hide yes)
			)
		)
		(pin "1"
		)
		(instances
			(project "k410t-devboard"
				(path ""
					(reference "#PWR0327")
					(unit 1)
				)
			)
		)
	)
	(symbol
		(lib_id "antmicroResistors0603:R_220R_0603")
		(at 262.89 237.49 90)
		(unit 1)
		(exclude_from_sim no)
		(in_bom yes)
		(on_board yes)
		(dnp no)
		(fields_autoplaced yes)
		(property "Reference" "R251"
			(at 265.43 233.6799 90)
			(effects
				(font
					(size 1.27 1.27)
				)
				(justify right)
			)
		)
		(property "Value" "R_220R_0603"
			(at 275.59 217.17 0)
			(effects
				(font
					(size 1.27 1.27)
					(thickness 0.15)
				)
				(justify left bottom)
				(hide yes)
			)
		)
		(property "Footprint" "antmicro-footprints:R_0603_1608Metric"
			(at 278.13 217.17 0)
			(effects
				(font
					(size 1.27 1.27)
					(thickness 0.15)
				)
				(justify left bottom)
				(hide yes)
			)
		)
		(property "Datasheet" "https://www.bourns.com/docs/product-datasheets/cr.pdf"
			(at 280.67 217.17 0)
			(effects
				(font
					(size 1.27 1.27)
					(thickness 0.15)
				)
				(justify left bottom)
				(hide yes)
			)
		)
		(property "Description" ""
			(at 262.89 237.49 0)
			(effects
				(font
					(size 1.27 1.27)
				)
			)
		)
		(property "Manufacturer" "Bourns"
			(at 285.75 217.17 0)
			(effects
				(font
					(size 1.27 1.27)
					(thickness 0.15)
				)
				(justify left bottom)
				(hide yes)
			)
		)
		(property "MPN" "CR0603-FX-2200ELF"
			(at 283.21 217.17 0)
			(effects
				(font
					(size 1.27 1.27)
					(thickness 0.15)
				)
				(justify left bottom)
				(hide yes)
			)
		)
		(property "Val" "220R"
			(at 265.43 236.2199 90)
			(effects
				(font
					(size 1.27 1.27)
					(thickness 0.15)
				)
				(justify right)
			)
		)
		(property "License" "Apache-2.0"
			(at 288.29 217.17 0)
			(effects
				(font
					(size 1.27 1.27)
					(thickness 0.15)
				)
				(justify left bottom)
				(hide yes)
			)
		)
		(property "Author" "Antmicro"
			(at 290.83 217.17 0)
			(effects
				(font
					(size 1.27 1.27)
					(thickness 0.15)
				)
				(justify left bottom)
				(hide yes)
			)
		)
		(property "Tolerance" "1%"
			(at 273.05 217.17 0)
			(effects
				(font
					(size 1.27 1.27)
				)
				(justify left bottom)
				(hide yes)
			)
		)
		(pin "1"
		)
		(pin "2"
		)
		(instances
			(project "k410t-devboard"
				(path ""
					(reference "R251")
					(unit 1)
				)
			)
		)
	)
	(symbol
		(lib_id "antmicropower:GND")
		(at 247.65 29.21 0)
		(mirror y)
		(unit 1)
		(exclude_from_sim no)
		(in_bom yes)
		(on_board yes)
		(dnp no)
		(fields_autoplaced yes)
		(property "Reference" "#PWR0324"
			(at 247.65 35.56 0)
			(effects
				(font
					(size 1.27 1.27)
				)
				(hide yes)
			)
		)
		(property "Value" "GND"
			(at 247.65 33.02 0)
			(effects
				(font
					(size 1.27 1.27)
				)
			)
		)
		(property "Footprint" ""
			(at 238.76 36.83 0)
			(effects
				(font
					(size 1.27 1.27)
					(thickness 0.15)
				)
				(justify left bottom)
				(hide yes)
			)
		)
		(property "Datasheet" ""
			(at 238.76 41.91 0)
			(effects
				(font
					(size 1.27 1.27)
					(thickness 0.15)
				)
				(justify left bottom)
				(hide yes)
			)
		)
		(property "Description" ""
			(at 247.65 29.21 0)
			(effects
				(font
					(size 1.27 1.27)
				)
			)
		)
		(property "Author" "Antmicro"
			(at 238.76 36.83 0)
			(effects
				(font
					(size 1.27 1.27)
					(thickness 0.15)
				)
				(justify left bottom)
				(hide yes)
			)
		)
		(property "License" "Apache-2.0"
			(at 238.76 39.37 0)
			(effects
				(font
					(size 1.27 1.27)
					(thickness 0.15)
				)
				(justify left bottom)
				(hide yes)
			)
		)
		(pin "1"
		)
		(instances
			(project "k410t-devboard"
				(path ""
					(reference "#PWR0324")
					(unit 1)
				)
			)
		)
	)
	(symbol
		(lib_id "antmicroCapacitors0402:C_100n_0402")
		(at 190.5 262.89 90)
		(unit 1)
		(exclude_from_sim no)
		(in_bom yes)
		(on_board yes)
		(dnp no)
		(fields_autoplaced yes)
		(property "Reference" "C269"
			(at 193.04 259.0735 90)
			(effects
				(font
					(size 1.27 1.27)
				)
				(justify right)
			)
		)
		(property "Value" "C_100n_0402"
			(at 200.66 242.57 0)
			(effects
				(font
					(size 1.27 1.27)
					(thickness 0.15)
				)
				(justify left bottom)
				(hide yes)
			)
		)
		(property "Footprint" "antmicro-footprints:C_0402_1005Metric"
			(at 203.2 242.57 0)
			(effects
				(font
					(size 1.27 1.27)
					(thickness 0.15)
				)
				(justify left bottom)
				(hide yes)
			)
		)
		(property "Datasheet" "https://www.murata.com/products/productdetail?partno=GRM155R61H104KE14%23"
			(at 205.74 242.57 0)
			(effects
				(font
					(size 1.27 1.27)
					(thickness 0.15)
				)
				(justify left bottom)
				(hide yes)
			)
		)
		(property "Description" ""
			(at 190.5 262.89 0)
			(effects
				(font
					(size 1.27 1.27)
				)
			)
		)
		(property "Manufacturer" "Murata"
			(at 210.82 242.57 0)
			(effects
				(font
					(size 1.27 1.27)
					(thickness 0.15)
				)
				(justify left bottom)
				(hide yes)
			)
		)
		(property "MPN" "GRM155R61H104KE14D"
			(at 208.28 242.57 0)
			(effects
				(font
					(size 1.27 1.27)
					(thickness 0.15)
				)
				(justify left bottom)
				(hide yes)
			)
		)
		(property "Val" "100n"
			(at 193.04 261.6135 90)
			(effects
				(font
					(size 1.27 1.27)
					(thickness 0.15)
				)
				(justify right)
			)
		)
		(property "License" "Apache-2.0"
			(at 213.36 242.57 0)
			(effects
				(font
					(size 1.27 1.27)
					(thickness 0.15)
				)
				(justify left bottom)
				(hide yes)
			)
		)
		(property "Author" "Antmicro"
			(at 215.9 242.57 0)
			(effects
				(font
					(size 1.27 1.27)
					(thickness 0.15)
				)
				(justify left bottom)
				(hide yes)
			)
		)
		(property "Voltage" "50V"
			(at 218.44 242.57 0)
			(effects
				(font
					(size 1.27 1.27)
				)
				(justify left bottom)
				(hide yes)
			)
		)
		(property "Dielectric" "X5R"
			(at 220.98 242.57 0)
			(effects
				(font
					(size 1.27 1.27)
				)
				(justify left bottom)
				(hide yes)
			)
		)
		(pin "1"
		)
		(pin "2"
		)
		(instances
			(project "k410t-devboard"
				(path ""
					(reference "C269")
					(unit 1)
				)
			)
		)
	)
	(symbol
		(lib_id "antmicropower:GND")
		(at 120.65 29.21 0)
		(unit 1)
		(exclude_from_sim no)
		(in_bom yes)
		(on_board yes)
		(dnp no)
		(fields_autoplaced yes)
		(property "Reference" "#PWR0289"
			(at 120.65 35.56 0)
			(effects
				(font
					(size 1.27 1.27)
				)
				(hide yes)
			)
		)
		(property "Value" "GND"
			(at 120.65 33.02 0)
			(effects
				(font
					(size 1.27 1.27)
				)
			)
		)
		(property "Footprint" ""
			(at 129.54 36.83 0)
			(effects
				(font
					(size 1.27 1.27)
					(thickness 0.15)
				)
				(justify left bottom)
				(hide yes)
			)
		)
		(property "Datasheet" ""
			(at 129.54 41.91 0)
			(effects
				(font
					(size 1.27 1.27)
					(thickness 0.15)
				)
				(justify left bottom)
				(hide yes)
			)
		)
		(property "Description" ""
			(at 120.65 29.21 0)
			(effects
				(font
					(size 1.27 1.27)
				)
			)
		)
		(property "Author" "Antmicro"
			(at 129.54 36.83 0)
			(effects
				(font
					(size 1.27 1.27)
					(thickness 0.15)
				)
				(justify left bottom)
				(hide yes)
			)
		)
		(property "License" "Apache-2.0"
			(at 129.54 39.37 0)
			(effects
				(font
					(size 1.27 1.27)
					(thickness 0.15)
				)
				(justify left bottom)
				(hide yes)
			)
		)
		(pin "1"
		)
		(instances
			(project "k410t-devboard"
				(path ""
					(reference "#PWR0289")
					(unit 1)
				)
			)
		)
	)
	(symbol
		(lib_id "antmicroResistors0402:R_10R_0402")
		(at 81.28 193.04 0)
		(unit 1)
		(exclude_from_sim no)
		(in_bom yes)
		(on_board yes)
		(dnp no)
		(property "Reference" "R233"
			(at 88.9 191.77 0)
			(effects
				(font
					(size 1.27 1.27)
				)
			)
		)
		(property "Value" "R_10R_0402"
			(at 101.6 205.74 0)
			(effects
				(font
					(size 1.27 1.27)
					(thickness 0.15)
				)
				(justify left bottom)
				(hide yes)
			)
		)
		(property "Footprint" "antmicro-footprints:R_0402_1005Metric"
			(at 101.6 208.28 0)
			(effects
				(font
					(size 1.27 1.27)
					(thickness 0.15)
				)
				(justify left bottom)
				(hide yes)
			)
		)
		(property "Datasheet" "https://www.bourns.com/docs/product-datasheets/cr.pdf"
			(at 101.6 210.82 0)
			(effects
				(font
					(size 1.27 1.27)
					(thickness 0.15)
				)
				(justify left bottom)
				(hide yes)
			)
		)
		(property "Description" ""
			(at 81.28 193.04 0)
			(effects
				(font
					(size 1.27 1.27)
				)
			)
		)
		(property "Manufacturer" "Bourns"
			(at 101.6 215.9 0)
			(effects
				(font
					(size 1.27 1.27)
					(thickness 0.15)
				)
				(justify left bottom)
				(hide yes)
			)
		)
		(property "MPN" "CR0402-FX-10R0GLF"
			(at 101.6 213.36 0)
			(effects
				(font
					(size 1.27 1.27)
					(thickness 0.15)
				)
				(justify left bottom)
				(hide yes)
			)
		)
		(property "Val" "10R"
			(at 79.375 191.77 0)
			(effects
				(font
					(size 1.27 1.27)
					(thickness 0.15)
				)
			)
		)
		(property "License" "Apache-2.0"
			(at 101.6 218.44 0)
			(effects
				(font
					(size 1.27 1.27)
					(thickness 0.15)
				)
				(justify left bottom)
				(hide yes)
			)
		)
		(property "Author" "Antmicro"
			(at 101.6 220.98 0)
			(effects
				(font
					(size 1.27 1.27)
					(thickness 0.15)
				)
				(justify left bottom)
				(hide yes)
			)
		)
		(property "Tolerance" "1%"
			(at 101.6 203.2 0)
			(effects
				(font
					(size 1.27 1.27)
				)
				(justify left bottom)
				(hide yes)
			)
		)
		(pin "1"
		)
		(pin "2"
		)
		(instances
			(project "k410t-devboard"
				(path ""
					(reference "R233")
					(unit 1)
				)
			)
		)
	)
	(symbol
		(lib_id "antmicroResistors0402:R_0R_0402")
		(at 342.9 168.91 0)
		(unit 1)
		(exclude_from_sim no)
		(in_bom yes)
		(on_board yes)
		(dnp no)
		(property "Reference" "R255"
			(at 350.52 167.64 0)
			(effects
				(font
					(size 1.27 1.27)
				)
			)
		)
		(property "Value" "R_0R_0402"
			(at 363.22 181.61 0)
			(effects
				(font
					(size 1.27 1.27)
					(thickness 0.15)
				)
				(justify left bottom)
				(hide yes)
			)
		)
		(property "Footprint" "antmicro-footprints:R_0402_1005Metric"
			(at 363.22 184.15 0)
			(effects
				(font
					(size 1.27 1.27)
					(thickness 0.15)
				)
				(justify left bottom)
				(hide yes)
			)
		)
		(property "Datasheet" "https://industrial.panasonic.com/cdbs/www-data/pdf/RDA0000/AOA0000C301.pdf"
			(at 363.22 186.69 0)
			(effects
				(font
					(size 1.27 1.27)
					(thickness 0.15)
				)
				(justify left bottom)
				(hide yes)
			)
		)
		(property "Description" ""
			(at 342.9 168.91 0)
			(effects
				(font
					(size 1.27 1.27)
				)
			)
		)
		(property "Manufacturer" "Panasonic"
			(at 363.22 191.77 0)
			(effects
				(font
					(size 1.27 1.27)
					(thickness 0.15)
				)
				(justify left bottom)
				(hide yes)
			)
		)
		(property "MPN" "ERJ2GE0R00X"
			(at 363.22 189.23 0)
			(effects
				(font
					(size 1.27 1.27)
					(thickness 0.15)
				)
				(justify left bottom)
				(hide yes)
			)
		)
		(property "Val" "0R"
			(at 341.63 167.64 0)
			(effects
				(font
					(size 1.27 1.27)
					(thickness 0.15)
				)
			)
		)
		(property "License" "Apache-2.0"
			(at 363.22 194.31 0)
			(effects
				(font
					(size 1.27 1.27)
					(thickness 0.15)
				)
				(justify left bottom)
				(hide yes)
			)
		)
		(property "Author" "Antmicro"
			(at 363.22 196.85 0)
			(effects
				(font
					(size 1.27 1.27)
					(thickness 0.15)
				)
				(justify left bottom)
				(hide yes)
			)
		)
		(property "Tolerance" "~"
			(at 363.22 179.07 0)
			(effects
				(font
					(size 1.27 1.27)
				)
				(justify left bottom)
				(hide yes)
			)
		)
		(property "Current" "1A"
			(at 363.22 199.39 0)
			(effects
				(font
					(size 1.27 1.27)
					(thickness 0.15)
				)
				(justify left bottom)
				(hide yes)
			)
		)
		(pin "1"
		)
		(pin "2"
		)
		(instances
			(project "k410t-devboard"
				(path ""
					(reference "R255")
					(unit 1)
				)
			)
		)
	)
	(symbol
		(lib_id "antmicroResistors0402:R_2k2_0402")
		(at 52.07 100.33 0)
		(unit 1)
		(exclude_from_sim no)
		(in_bom yes)
		(on_board yes)
		(dnp no)
		(property "Reference" "R213"
			(at 59.69 99.06 0)
			(effects
				(font
					(size 1.27 1.27)
				)
			)
		)
		(property "Value" "R_2k2_0402"
			(at 72.39 113.03 0)
			(effects
				(font
					(size 1.27 1.27)
					(thickness 0.15)
				)
				(justify left bottom)
				(hide yes)
			)
		)
		(property "Footprint" "antmicro-footprints:R_0402_1005Metric"
			(at 72.39 115.57 0)
			(effects
				(font
					(size 1.27 1.27)
					(thickness 0.15)
				)
				(justify left bottom)
				(hide yes)
			)
		)
		(property "Datasheet" "https://www.bourns.com/docs/product-datasheets/cr.pdf"
			(at 72.39 118.11 0)
			(effects
				(font
					(size 1.27 1.27)
					(thickness 0.15)
				)
				(justify left bottom)
				(hide yes)
			)
		)
		(property "Description" ""
			(at 52.07 100.33 0)
			(effects
				(font
					(size 1.27 1.27)
				)
			)
		)
		(property "Manufacturer" "Bourns"
			(at 72.39 123.19 0)
			(effects
				(font
					(size 1.27 1.27)
					(thickness 0.15)
				)
				(justify left bottom)
				(hide yes)
			)
		)
		(property "MPN" "CR0402-FX-2201GLF"
			(at 72.39 120.65 0)
			(effects
				(font
					(size 1.27 1.27)
					(thickness 0.15)
				)
				(justify left bottom)
				(hide yes)
			)
		)
		(property "Val" "2k2"
			(at 50.165 99.06 0)
			(effects
				(font
					(size 1.27 1.27)
					(thickness 0.15)
				)
			)
		)
		(property "License" "Apache-2.0"
			(at 72.39 125.73 0)
			(effects
				(font
					(size 1.27 1.27)
					(thickness 0.15)
				)
				(justify left bottom)
				(hide yes)
			)
		)
		(property "Author" "Antmicro"
			(at 72.39 128.27 0)
			(effects
				(font
					(size 1.27 1.27)
					(thickness 0.15)
				)
				(justify left bottom)
				(hide yes)
			)
		)
		(property "Tolerance" "1%"
			(at 72.39 110.49 0)
			(effects
				(font
					(size 1.27 1.27)
				)
				(justify left bottom)
				(hide yes)
			)
		)
		(pin "1"
		)
		(pin "2"
		)
		(instances
			(project "k410t-devboard"
				(path ""
					(reference "R213")
					(unit 1)
				)
			)
		)
	)
	(symbol
		(lib_id "antmicroCapacitors0402:C_100n_0402")
		(at 184.15 175.26 90)
		(mirror x)
		(unit 1)
		(exclude_from_sim no)
		(in_bom yes)
		(on_board yes)
		(dnp no)
		(property "Reference" "C268"
			(at 184.785 175.895 90)
			(effects
				(font
					(size 1.27 1.27)
				)
				(justify right)
			)
		)
		(property "Value" "C_100n_0402"
			(at 194.31 195.58 0)
			(effects
				(font
					(size 1.27 1.27)
					(thickness 0.15)
				)
				(justify left bottom)
				(hide yes)
			)
		)
		(property "Footprint" "antmicro-footprints:C_0402_1005Metric"
			(at 196.85 195.58 0)
			(effects
				(font
					(size 1.27 1.27)
					(thickness 0.15)
				)
				(justify left bottom)
				(hide yes)
			)
		)
		(property "Datasheet" "https://www.murata.com/products/productdetail?partno=GRM155R61H104KE14%23"
			(at 199.39 195.58 0)
			(effects
				(font
					(size 1.27 1.27)
					(thickness 0.15)
				)
				(justify left bottom)
				(hide yes)
			)
		)
		(property "Description" ""
			(at 184.15 175.26 0)
			(effects
				(font
					(size 1.27 1.27)
				)
			)
		)
		(property "Manufacturer" "Murata"
			(at 204.47 195.58 0)
			(effects
				(font
					(size 1.27 1.27)
					(thickness 0.15)
				)
				(justify left bottom)
				(hide yes)
			)
		)
		(property "MPN" "GRM155R61H104KE14D"
			(at 201.93 195.58 0)
			(effects
				(font
					(size 1.27 1.27)
					(thickness 0.15)
				)
				(justify left bottom)
				(hide yes)
			)
		)
		(property "Val" "100n"
			(at 184.785 179.705 90)
			(effects
				(font
					(size 1.27 1.27)
					(thickness 0.15)
				)
				(justify right)
			)
		)
		(property "License" "Apache-2.0"
			(at 207.01 195.58 0)
			(effects
				(font
					(size 1.27 1.27)
					(thickness 0.15)
				)
				(justify left bottom)
				(hide yes)
			)
		)
		(property "Author" "Antmicro"
			(at 209.55 195.58 0)
			(effects
				(font
					(size 1.27 1.27)
					(thickness 0.15)
				)
				(justify left bottom)
				(hide yes)
			)
		)
		(property "Voltage" "50V"
			(at 212.09 195.58 0)
			(effects
				(font
					(size 1.27 1.27)
				)
				(justify left bottom)
				(hide yes)
			)
		)
		(property "Dielectric" "X5R"
			(at 214.63 195.58 0)
			(effects
				(font
					(size 1.27 1.27)
				)
				(justify left bottom)
				(hide yes)
			)
		)
		(pin "1"
		)
		(pin "2"
		)
		(instances
			(project "k410t-devboard"
				(path ""
					(reference "C268")
					(unit 1)
				)
			)
		)
	)
	(symbol
		(lib_id "antmicroResistors0402:R_10k_0402")
		(at 52.07 81.28 0)
		(unit 1)
		(exclude_from_sim no)
		(in_bom yes)
		(on_board yes)
		(dnp no)
		(property "Reference" "R208"
			(at 59.69 80.01 0)
			(effects
				(font
					(size 1.27 1.27)
				)
			)
		)
		(property "Value" "R_10k_0402"
			(at 72.39 93.98 0)
			(effects
				(font
					(size 1.27 1.27)
					(thickness 0.15)
				)
				(justify left bottom)
				(hide yes)
			)
		)
		(property "Footprint" "antmicro-footprints:R_0402_1005Metric"
			(at 72.39 96.52 0)
			(effects
				(font
					(size 1.27 1.27)
					(thickness 0.15)
				)
				(justify left bottom)
				(hide yes)
			)
		)
		(property "Datasheet" "https://www.bourns.com/docs/product-datasheets/cr.pdf"
			(at 72.39 99.06 0)
			(effects
				(font
					(size 1.27 1.27)
					(thickness 0.15)
				)
				(justify left bottom)
				(hide yes)
			)
		)
		(property "Description" ""
			(at 52.07 81.28 0)
			(effects
				(font
					(size 1.27 1.27)
				)
			)
		)
		(property "Manufacturer" "Bourns"
			(at 72.39 104.14 0)
			(effects
				(font
					(size 1.27 1.27)
					(thickness 0.15)
				)
				(justify left bottom)
				(hide yes)
			)
		)
		(property "MPN" "CR0402-FX-1002GLF"
			(at 72.39 101.6 0)
			(effects
				(font
					(size 1.27 1.27)
					(thickness 0.15)
				)
				(justify left bottom)
				(hide yes)
			)
		)
		(property "Val" "10k"
			(at 50.165 80.01 0)
			(effects
				(font
					(size 1.27 1.27)
					(thickness 0.15)
				)
			)
		)
		(property "License" "Apache-2.0"
			(at 72.39 106.68 0)
			(effects
				(font
					(size 1.27 1.27)
					(thickness 0.15)
				)
				(justify left bottom)
				(hide yes)
			)
		)
		(property "Author" "Antmicro"
			(at 72.39 109.22 0)
			(effects
				(font
					(size 1.27 1.27)
					(thickness 0.15)
				)
				(justify left bottom)
				(hide yes)
			)
		)
		(property "Tolerance" "1%"
			(at 72.39 91.44 0)
			(effects
				(font
					(size 1.27 1.27)
				)
				(justify left bottom)
				(hide yes)
			)
		)
		(pin "1"
		)
		(pin "2"
		)
		(instances
			(project "k410t-devboard"
				(path ""
					(reference "R208")
					(unit 1)
				)
			)
		)
	)
	(symbol
		(lib_id "antmicroResistors0402:R_10R_0402")
		(at 105.41 203.2 0)
		(unit 1)
		(exclude_from_sim no)
		(in_bom yes)
		(on_board yes)
		(dnp no)
		(property "Reference" "R237"
			(at 113.03 201.93 0)
			(effects
				(font
					(size 1.27 1.27)
				)
			)
		)
		(property "Value" "R_10R_0402"
			(at 125.73 215.9 0)
			(effects
				(font
					(size 1.27 1.27)
					(thickness 0.15)
				)
				(justify left bottom)
				(hide yes)
			)
		)
		(property "Footprint" "antmicro-footprints:R_0402_1005Metric"
			(at 125.73 218.44 0)
			(effects
				(font
					(size 1.27 1.27)
					(thickness 0.15)
				)
				(justify left bottom)
				(hide yes)
			)
		)
		(property "Datasheet" "https://www.bourns.com/docs/product-datasheets/cr.pdf"
			(at 125.73 220.98 0)
			(effects
				(font
					(size 1.27 1.27)
					(thickness 0.15)
				)
				(justify left bottom)
				(hide yes)
			)
		)
		(property "Description" ""
			(at 105.41 203.2 0)
			(effects
				(font
					(size 1.27 1.27)
				)
			)
		)
		(property "Manufacturer" "Bourns"
			(at 125.73 226.06 0)
			(effects
				(font
					(size 1.27 1.27)
					(thickness 0.15)
				)
				(justify left bottom)
				(hide yes)
			)
		)
		(property "MPN" "CR0402-FX-10R0GLF"
			(at 125.73 223.52 0)
			(effects
				(font
					(size 1.27 1.27)
					(thickness 0.15)
				)
				(justify left bottom)
				(hide yes)
			)
		)
		(property "Val" "10R"
			(at 103.505 201.93 0)
			(effects
				(font
					(size 1.27 1.27)
					(thickness 0.15)
				)
			)
		)
		(property "License" "Apache-2.0"
			(at 125.73 228.6 0)
			(effects
				(font
					(size 1.27 1.27)
					(thickness 0.15)
				)
				(justify left bottom)
				(hide yes)
			)
		)
		(property "Author" "Antmicro"
			(at 125.73 231.14 0)
			(effects
				(font
					(size 1.27 1.27)
					(thickness 0.15)
				)
				(justify left bottom)
				(hide yes)
			)
		)
		(property "Tolerance" "1%"
			(at 125.73 213.36 0)
			(effects
				(font
					(size 1.27 1.27)
				)
				(justify left bottom)
				(hide yes)
			)
		)
		(pin "1"
		)
		(pin "2"
		)
		(instances
			(project "k410t-devboard"
				(path ""
					(reference "R237")
					(unit 1)
				)
			)
		)
	)
	(symbol
		(lib_id "antmicroResistors0402:R_10R_0402")
		(at 105.41 205.74 0)
		(unit 1)
		(exclude_from_sim no)
		(in_bom yes)
		(on_board yes)
		(dnp no)
		(property "Reference" "R238"
			(at 113.03 204.47 0)
			(effects
				(font
					(size 1.27 1.27)
				)
			)
		)
		(property "Value" "R_10R_0402"
			(at 125.73 218.44 0)
			(effects
				(font
					(size 1.27 1.27)
					(thickness 0.15)
				)
				(justify left bottom)
				(hide yes)
			)
		)
		(property "Footprint" "antmicro-footprints:R_0402_1005Metric"
			(at 125.73 220.98 0)
			(effects
				(font
					(size 1.27 1.27)
					(thickness 0.15)
				)
				(justify left bottom)
				(hide yes)
			)
		)
		(property "Datasheet" "https://www.bourns.com/docs/product-datasheets/cr.pdf"
			(at 125.73 223.52 0)
			(effects
				(font
					(size 1.27 1.27)
					(thickness 0.15)
				)
				(justify left bottom)
				(hide yes)
			)
		)
		(property "Description" ""
			(at 105.41 205.74 0)
			(effects
				(font
					(size 1.27 1.27)
				)
			)
		)
		(property "Manufacturer" "Bourns"
			(at 125.73 228.6 0)
			(effects
				(font
					(size 1.27 1.27)
					(thickness 0.15)
				)
				(justify left bottom)
				(hide yes)
			)
		)
		(property "MPN" "CR0402-FX-10R0GLF"
			(at 125.73 226.06 0)
			(effects
				(font
					(size 1.27 1.27)
					(thickness 0.15)
				)
				(justify left bottom)
				(hide yes)
			)
		)
		(property "Val" "10R"
			(at 103.505 204.47 0)
			(effects
				(font
					(size 1.27 1.27)
					(thickness 0.15)
				)
			)
		)
		(property "License" "Apache-2.0"
			(at 125.73 231.14 0)
			(effects
				(font
					(size 1.27 1.27)
					(thickness 0.15)
				)
				(justify left bottom)
				(hide yes)
			)
		)
		(property "Author" "Antmicro"
			(at 125.73 233.68 0)
			(effects
				(font
					(size 1.27 1.27)
					(thickness 0.15)
				)
				(justify left bottom)
				(hide yes)
			)
		)
		(property "Tolerance" "1%"
			(at 125.73 215.9 0)
			(effects
				(font
					(size 1.27 1.27)
				)
				(justify left bottom)
				(hide yes)
			)
		)
		(pin "1"
		)
		(pin "2"
		)
		(instances
			(project "k410t-devboard"
				(path ""
					(reference "R238")
					(unit 1)
				)
			)
		)
	)
	(symbol
		(lib_id "antmicroCapacitors0402:C_100n_0402")
		(at 130.81 43.18 90)
		(unit 1)
		(exclude_from_sim no)
		(in_bom yes)
		(on_board yes)
		(dnp no)
		(fields_autoplaced yes)
		(property "Reference" "C260"
			(at 133.35 39.3635 90)
			(effects
				(font
					(size 1.27 1.27)
				)
				(justify right)
			)
		)
		(property "Value" "C_100n_0402"
			(at 140.97 22.86 0)
			(effects
				(font
					(size 1.27 1.27)
					(thickness 0.15)
				)
				(justify left bottom)
				(hide yes)
			)
		)
		(property "Footprint" "antmicro-footprints:C_0402_1005Metric"
			(at 143.51 22.86 0)
			(effects
				(font
					(size 1.27 1.27)
					(thickness 0.15)
				)
				(justify left bottom)
				(hide yes)
			)
		)
		(property "Datasheet" "https://www.murata.com/products/productdetail?partno=GRM155R61H104KE14%23"
			(at 146.05 22.86 0)
			(effects
				(font
					(size 1.27 1.27)
					(thickness 0.15)
				)
				(justify left bottom)
				(hide yes)
			)
		)
		(property "Description" ""
			(at 130.81 43.18 0)
			(effects
				(font
					(size 1.27 1.27)
				)
			)
		)
		(property "Manufacturer" "Murata"
			(at 151.13 22.86 0)
			(effects
				(font
					(size 1.27 1.27)
					(thickness 0.15)
				)
				(justify left bottom)
				(hide yes)
			)
		)
		(property "MPN" "GRM155R61H104KE14D"
			(at 148.59 22.86 0)
			(effects
				(font
					(size 1.27 1.27)
					(thickness 0.15)
				)
				(justify left bottom)
				(hide yes)
			)
		)
		(property "Val" "100n"
			(at 133.35 41.9035 90)
			(effects
				(font
					(size 1.27 1.27)
					(thickness 0.15)
				)
				(justify right)
			)
		)
		(property "License" "Apache-2.0"
			(at 153.67 22.86 0)
			(effects
				(font
					(size 1.27 1.27)
					(thickness 0.15)
				)
				(justify left bottom)
				(hide yes)
			)
		)
		(property "Author" "Antmicro"
			(at 156.21 22.86 0)
			(effects
				(font
					(size 1.27 1.27)
					(thickness 0.15)
				)
				(justify left bottom)
				(hide yes)
			)
		)
		(property "Voltage" "50V"
			(at 158.75 22.86 0)
			(effects
				(font
					(size 1.27 1.27)
				)
				(justify left bottom)
				(hide yes)
			)
		)
		(property "Dielectric" "X5R"
			(at 161.29 22.86 0)
			(effects
				(font
					(size 1.27 1.27)
				)
				(justify left bottom)
				(hide yes)
			)
		)
		(pin "1"
		)
		(pin "2"
		)
		(instances
			(project "k410t-devboard"
				(path ""
					(reference "C260")
					(unit 1)
				)
			)
		)
	)
	(symbol
		(lib_id "antmicroCapacitors0402:C_10u_0402")
		(at 120.65 43.18 90)
		(unit 1)
		(exclude_from_sim no)
		(in_bom yes)
		(on_board yes)
		(dnp no)
		(fields_autoplaced yes)
		(property "Reference" "C255"
			(at 123.825 39.3635 90)
			(effects
				(font
					(size 1.27 1.27)
				)
				(justify right)
			)
		)
		(property "Value" "C_10u_0402"
			(at 130.81 22.86 0)
			(effects
				(font
					(size 1.27 1.27)
					(thickness 0.15)
				)
				(justify left bottom)
				(hide yes)
			)
		)
		(property "Footprint" "antmicro-footprints:C_0402_1005Metric"
			(at 133.35 22.86 0)
			(effects
				(font
					(size 1.27 1.27)
					(thickness 0.15)
				)
				(justify left bottom)
				(hide yes)
			)
		)
		(property "Datasheet" "https://www.yageo.com/en/Chart/Download/pdf/CC0402MRX5R5BB106"
			(at 135.89 22.86 0)
			(effects
				(font
					(size 1.27 1.27)
					(thickness 0.15)
				)
				(justify left bottom)
				(hide yes)
			)
		)
		(property "Description" ""
			(at 120.65 43.18 0)
			(effects
				(font
					(size 1.27 1.27)
				)
			)
		)
		(property "Manufacturer" "YAGEO"
			(at 140.97 22.86 0)
			(effects
				(font
					(size 1.27 1.27)
					(thickness 0.15)
				)
				(justify left bottom)
				(hide yes)
			)
		)
		(property "MPN" "CC0402MRX5R5BB106"
			(at 138.43 22.86 0)
			(effects
				(font
					(size 1.27 1.27)
					(thickness 0.15)
				)
				(justify left bottom)
				(hide yes)
			)
		)
		(property "Val" "10u"
			(at 123.825 41.9035 90)
			(effects
				(font
					(size 1.27 1.27)
					(thickness 0.15)
				)
				(justify right)
			)
		)
		(property "License" "Apache-2.0"
			(at 143.51 22.86 0)
			(effects
				(font
					(size 1.27 1.27)
					(thickness 0.15)
				)
				(justify left bottom)
				(hide yes)
			)
		)
		(property "Author" "Antmicro"
			(at 146.05 22.86 0)
			(effects
				(font
					(size 1.27 1.27)
					(thickness 0.15)
				)
				(justify left bottom)
				(hide yes)
			)
		)
		(property "Voltage" ""
			(at 148.59 22.86 0)
			(effects
				(font
					(size 1.27 1.27)
				)
				(justify left bottom)
				(hide yes)
			)
		)
		(property "Dielectric" ""
			(at 151.13 22.86 0)
			(effects
				(font
					(size 1.27 1.27)
				)
				(justify left bottom)
				(hide yes)
			)
		)
		(pin "1"
		)
		(pin "2"
		)
		(instances
			(project "k410t-devboard"
				(path ""
					(reference "C255")
					(unit 1)
				)
			)
		)
	)
	(symbol
		(lib_id "antmicropower:GND")
		(at 379.73 129.54 0)
		(unit 1)
		(exclude_from_sim no)
		(in_bom yes)
		(on_board yes)
		(dnp no)
		(property "Reference" "#PWR0345"
			(at 379.73 135.89 0)
			(effects
				(font
					(size 1.27 1.27)
				)
				(hide yes)
			)
		)
		(property "Value" "GND"
			(at 379.73 133.35 0)
			(effects
				(font
					(size 1.27 1.27)
				)
			)
		)
		(property "Footprint" ""
			(at 388.62 137.16 0)
			(effects
				(font
					(size 1.27 1.27)
					(thickness 0.15)
				)
				(justify left bottom)
				(hide yes)
			)
		)
		(property "Datasheet" ""
			(at 388.62 142.24 0)
			(effects
				(font
					(size 1.27 1.27)
					(thickness 0.15)
				)
				(justify left bottom)
				(hide yes)
			)
		)
		(property "Description" ""
			(at 379.73 129.54 0)
			(effects
				(font
					(size 1.27 1.27)
				)
			)
		)
		(property "Author" "Antmicro"
			(at 388.62 137.16 0)
			(effects
				(font
					(size 1.27 1.27)
					(thickness 0.15)
				)
				(justify left bottom)
				(hide yes)
			)
		)
		(property "License" "Apache-2.0"
			(at 388.62 139.7 0)
			(effects
				(font
					(size 1.27 1.27)
					(thickness 0.15)
				)
				(justify left bottom)
				(hide yes)
			)
		)
		(pin "1"
		)
		(instances
			(project "k410t-devboard"
				(path ""
					(reference "#PWR0345")
					(unit 1)
				)
			)
		)
	)
	(symbol
		(lib_id "antmicroCapacitors0402:C_100n_0402")
		(at 280.67 43.18 90)
		(unit 1)
		(exclude_from_sim no)
		(in_bom yes)
		(on_board yes)
		(dnp no)
		(property "Reference" "C289"
			(at 281.305 38.735 90)
			(effects
				(font
					(size 1.27 1.27)
				)
				(justify right)
			)
		)
		(property "Value" "C_100n_0402"
			(at 290.83 22.86 0)
			(effects
				(font
					(size 1.27 1.27)
					(thickness 0.15)
				)
				(justify left bottom)
				(hide yes)
			)
		)
		(property "Footprint" "antmicro-footprints:C_0402_1005Metric"
			(at 293.37 22.86 0)
			(effects
				(font
					(size 1.27 1.27)
					(thickness 0.15)
				)
				(justify left bottom)
				(hide yes)
			)
		)
		(property "Datasheet" "https://www.murata.com/products/productdetail?partno=GRM155R61H104KE14%23"
			(at 295.91 22.86 0)
			(effects
				(font
					(size 1.27 1.27)
					(thickness 0.15)
				)
				(justify left bottom)
				(hide yes)
			)
		)
		(property "Description" ""
			(at 280.67 43.18 0)
			(effects
				(font
					(size 1.27 1.27)
				)
			)
		)
		(property "Manufacturer" "Murata"
			(at 300.99 22.86 0)
			(effects
				(font
					(size 1.27 1.27)
					(thickness 0.15)
				)
				(justify left bottom)
				(hide yes)
			)
		)
		(property "MPN" "GRM155R61H104KE14D"
			(at 298.45 22.86 0)
			(effects
				(font
					(size 1.27 1.27)
					(thickness 0.15)
				)
				(justify left bottom)
				(hide yes)
			)
		)
		(property "Val" "100n"
			(at 281.305 42.545 90)
			(effects
				(font
					(size 1.27 1.27)
					(thickness 0.15)
				)
				(justify right)
			)
		)
		(property "License" "Apache-2.0"
			(at 303.53 22.86 0)
			(effects
				(font
					(size 1.27 1.27)
					(thickness 0.15)
				)
				(justify left bottom)
				(hide yes)
			)
		)
		(property "Author" "Antmicro"
			(at 306.07 22.86 0)
			(effects
				(font
					(size 1.27 1.27)
					(thickness 0.15)
				)
				(justify left bottom)
				(hide yes)
			)
		)
		(property "Voltage" "50V"
			(at 308.61 22.86 0)
			(effects
				(font
					(size 1.27 1.27)
				)
				(justify left bottom)
				(hide yes)
			)
		)
		(property "Dielectric" "X5R"
			(at 311.15 22.86 0)
			(effects
				(font
					(size 1.27 1.27)
				)
				(justify left bottom)
				(hide yes)
			)
		)
		(pin "1"
		)
		(pin "2"
		)
		(instances
			(project "k410t-devboard"
				(path ""
					(reference "C289")
					(unit 1)
				)
			)
		)
	)
	(symbol
		(lib_id "antmicroResonators:Resonator_25MHz_ABM8G")
		(at 130.81 120.65 0)
		(unit 1)
		(exclude_from_sim no)
		(in_bom yes)
		(on_board yes)
		(dnp no)
		(property "Reference" "Y4"
			(at 134.62 114.3 0)
			(effects
				(font
					(size 1.27 1.27)
				)
			)
		)
		(property "Value" "Resonator_25MHz_ABM8G"
			(at 146.05 133.35 0)
			(effects
				(font
					(size 1.27 1.27)
					(thickness 0.15)
				)
				(justify left bottom)
				(hide yes)
			)
		)
		(property "Footprint" "antmicro-footprints:Resonator_SMD_Abracon_ABM8G_3.2x2.5mm"
			(at 146.05 135.89 0)
			(effects
				(font
					(size 1.27 1.27)
					(thickness 0.15)
				)
				(justify left bottom)
				(hide yes)
			)
		)
		(property "Datasheet" "https://abracon.com/Resonators/ABM8G.pdf"
			(at 146.05 138.43 0)
			(effects
				(font
					(size 1.27 1.27)
					(thickness 0.15)
				)
				(justify left bottom)
				(hide yes)
			)
		)
		(property "Description" ""
			(at 130.81 120.65 0)
			(effects
				(font
					(size 1.27 1.27)
				)
			)
		)
		(property "MPN" "ABM8G-25.000MHZ-18-D2Y-T3"
			(at 146.05 128.27 0)
			(effects
				(font
					(size 1.27 1.27)
					(thickness 0.15)
				)
				(justify left bottom)
				(hide yes)
			)
		)
		(property "Manufacturer" "Abracon"
			(at 146.05 140.97 0)
			(effects
				(font
					(size 1.27 1.27)
					(thickness 0.15)
				)
				(justify left bottom)
				(hide yes)
			)
		)
		(property "Val" "25 MHz"
			(at 134.62 116.84 0)
			(effects
				(font
					(size 1.27 1.27)
					(thickness 0.15)
				)
			)
		)
		(property "Author" "Antmicro"
			(at 146.05 143.51 0)
			(effects
				(font
					(size 1.27 1.27)
					(thickness 0.15)
				)
				(justify left bottom)
				(hide yes)
			)
		)
		(property "License" "Apache-2.0"
			(at 146.05 146.05 0)
			(effects
				(font
					(size 1.27 1.27)
					(thickness 0.15)
				)
				(justify left bottom)
				(hide yes)
			)
		)
		(pin "1"
		)
		(pin "2"
		)
		(pin "3"
		)
		(pin "4"
		)
		(instances
			(project "k410t-devboard"
				(path ""
					(reference "Y4")
					(unit 1)
				)
			)
		)
	)
	(symbol
		(lib_id "antmicropower:GND")
		(at 208.28 209.55 0)
		(unit 1)
		(exclude_from_sim no)
		(in_bom yes)
		(on_board yes)
		(dnp no)
		(property "Reference" "#PWR0314"
			(at 208.28 215.9 0)
			(effects
				(font
					(size 1.27 1.27)
				)
				(hide yes)
			)
		)
		(property "Value" "GND"
			(at 208.28 213.36 0)
			(effects
				(font
					(size 1.27 1.27)
				)
			)
		)
		(property "Footprint" ""
			(at 217.17 217.17 0)
			(effects
				(font
					(size 1.27 1.27)
					(thickness 0.15)
				)
				(justify left bottom)
				(hide yes)
			)
		)
		(property "Datasheet" ""
			(at 217.17 222.25 0)
			(effects
				(font
					(size 1.27 1.27)
					(thickness 0.15)
				)
				(justify left bottom)
				(hide yes)
			)
		)
		(property "Description" ""
			(at 208.28 209.55 0)
			(effects
				(font
					(size 1.27 1.27)
				)
			)
		)
		(property "Author" "Antmicro"
			(at 217.17 217.17 0)
			(effects
				(font
					(size 1.27 1.27)
					(thickness 0.15)
				)
				(justify left bottom)
				(hide yes)
			)
		)
		(property "License" "Apache-2.0"
			(at 217.17 219.71 0)
			(effects
				(font
					(size 1.27 1.27)
					(thickness 0.15)
				)
				(justify left bottom)
				(hide yes)
			)
		)
		(pin "1"
		)
		(instances
			(project "k410t-devboard"
				(path ""
					(reference "#PWR0314")
					(unit 1)
				)
			)
		)
	)
	(symbol
		(lib_id "antmicroResistors0402:R_10k_0402")
		(at 52.07 78.74 0)
		(unit 1)
		(exclude_from_sim no)
		(in_bom no)
		(on_board yes)
		(dnp yes)
		(property "Reference" "R207"
			(at 59.69 77.47 0)
			(effects
				(font
					(size 1.27 1.27)
				)
			)
		)
		(property "Value" "R_10k_0402"
			(at 72.39 91.44 0)
			(effects
				(font
					(size 1.27 1.27)
					(thickness 0.15)
				)
				(justify left bottom)
				(hide yes)
			)
		)
		(property "Footprint" "antmicro-footprints:R_0402_1005Metric"
			(at 72.39 93.98 0)
			(effects
				(font
					(size 1.27 1.27)
					(thickness 0.15)
				)
				(justify left bottom)
				(hide yes)
			)
		)
		(property "Datasheet" "https://www.bourns.com/docs/product-datasheets/cr.pdf"
			(at 72.39 96.52 0)
			(effects
				(font
					(size 1.27 1.27)
					(thickness 0.15)
				)
				(justify left bottom)
				(hide yes)
			)
		)
		(property "Description" ""
			(at 52.07 78.74 0)
			(effects
				(font
					(size 1.27 1.27)
				)
			)
		)
		(property "Manufacturer" "Bourns"
			(at 72.39 101.6 0)
			(effects
				(font
					(size 1.27 1.27)
					(thickness 0.15)
				)
				(justify left bottom)
				(hide yes)
			)
		)
		(property "MPN" "CR0402-FX-1002GLF"
			(at 72.39 99.06 0)
			(effects
				(font
					(size 1.27 1.27)
					(thickness 0.15)
				)
				(justify left bottom)
				(hide yes)
			)
		)
		(property "Val" "10k"
			(at 50.165 77.47 0)
			(effects
				(font
					(size 1.27 1.27)
					(thickness 0.15)
				)
			)
		)
		(property "DNP" "DNP"
			(at 54.61 78.74 0)
			(effects
				(font
					(size 1.27 1.27)
				)
			)
		)
		(property "License" "Apache-2.0"
			(at 72.39 104.14 0)
			(effects
				(font
					(size 1.27 1.27)
					(thickness 0.15)
				)
				(justify left bottom)
				(hide yes)
			)
		)
		(property "Author" "Antmicro"
			(at 72.39 106.68 0)
			(effects
				(font
					(size 1.27 1.27)
					(thickness 0.15)
				)
				(justify left bottom)
				(hide yes)
			)
		)
		(property "Tolerance" "1%"
			(at 72.39 88.9 0)
			(effects
				(font
					(size 1.27 1.27)
				)
				(justify left bottom)
				(hide yes)
			)
		)
		(pin "1"
		)
		(pin "2"
		)
		(instances
			(project "k410t-devboard"
				(path ""
					(reference "R207")
					(unit 1)
				)
			)
		)
	)
	(symbol
		(lib_id "antmicroResistors0402:R_12k_0402")
		(at 184.15 220.98 90)
		(unit 1)
		(exclude_from_sim no)
		(in_bom yes)
		(on_board yes)
		(dnp no)
		(property "Reference" "R244"
			(at 185.42 217.17 90)
			(effects
				(font
					(size 1.27 1.27)
				)
				(justify right)
			)
		)
		(property "Value" "R_12k_0402"
			(at 196.85 200.66 0)
			(effects
				(font
					(size 1.27 1.27)
					(thickness 0.15)
				)
				(justify left bottom)
				(hide yes)
			)
		)
		(property "Footprint" "antmicro-footprints:R_0402_1005Metric"
			(at 199.39 200.66 0)
			(effects
				(font
					(size 1.27 1.27)
					(thickness 0.15)
				)
				(justify left bottom)
				(hide yes)
			)
		)
		(property "Datasheet" "https://www.bourns.com/docs/product-datasheets/cr.pdf"
			(at 201.93 200.66 0)
			(effects
				(font
					(size 1.27 1.27)
					(thickness 0.15)
				)
				(justify left bottom)
				(hide yes)
			)
		)
		(property "Description" ""
			(at 184.15 220.98 0)
			(effects
				(font
					(size 1.27 1.27)
				)
			)
		)
		(property "Manufacturer" "Bourns"
			(at 207.01 200.66 0)
			(effects
				(font
					(size 1.27 1.27)
					(thickness 0.15)
				)
				(justify left bottom)
				(hide yes)
			)
		)
		(property "MPN" "CR0402-FX-1202GLF"
			(at 204.47 200.66 0)
			(effects
				(font
					(size 1.27 1.27)
					(thickness 0.15)
				)
				(justify left bottom)
				(hide yes)
			)
		)
		(property "Val" "12k"
			(at 185.42 219.71 90)
			(effects
				(font
					(size 1.27 1.27)
					(thickness 0.15)
				)
				(justify right)
			)
		)
		(property "License" "Apache-2.0"
			(at 209.55 200.66 0)
			(effects
				(font
					(size 1.27 1.27)
					(thickness 0.15)
				)
				(justify left bottom)
				(hide yes)
			)
		)
		(property "Author" "Antmicro"
			(at 212.09 200.66 0)
			(effects
				(font
					(size 1.27 1.27)
					(thickness 0.15)
				)
				(justify left bottom)
				(hide yes)
			)
		)
		(property "Tolerance" "1%"
			(at 194.31 200.66 0)
			(effects
				(font
					(size 1.27 1.27)
				)
				(justify left bottom)
				(hide yes)
			)
		)
		(pin "1"
		)
		(pin "2"
		)
		(instances
			(project "k410t-devboard"
				(path ""
					(reference "R244")
					(unit 1)
				)
			)
		)
	)
	(symbol
		(lib_id "antmicropower:GND")
		(at 68.58 270.51 0)
		(unit 1)
		(exclude_from_sim no)
		(in_bom yes)
		(on_board yes)
		(dnp no)
		(property "Reference" "#PWR0285"
			(at 68.58 276.86 0)
			(effects
				(font
					(size 1.27 1.27)
				)
				(hide yes)
			)
		)
		(property "Value" "GND"
			(at 68.58 274.32 0)
			(effects
				(font
					(size 1.27 1.27)
				)
			)
		)
		(property "Footprint" ""
			(at 77.47 278.13 0)
			(effects
				(font
					(size 1.27 1.27)
					(thickness 0.15)
				)
				(justify left bottom)
				(hide yes)
			)
		)
		(property "Datasheet" ""
			(at 77.47 283.21 0)
			(effects
				(font
					(size 1.27 1.27)
					(thickness 0.15)
				)
				(justify left bottom)
				(hide yes)
			)
		)
		(property "Description" ""
			(at 68.58 270.51 0)
			(effects
				(font
					(size 1.27 1.27)
				)
			)
		)
		(property "Author" "Antmicro"
			(at 77.47 278.13 0)
			(effects
				(font
					(size 1.27 1.27)
					(thickness 0.15)
				)
				(justify left bottom)
				(hide yes)
			)
		)
		(property "License" "Apache-2.0"
			(at 77.47 280.67 0)
			(effects
				(font
					(size 1.27 1.27)
					(thickness 0.15)
				)
				(justify left bottom)
				(hide yes)
			)
		)
		(pin "1"
		)
		(instances
			(project "k410t-devboard"
				(path ""
					(reference "#PWR0285")
					(unit 1)
				)
			)
		)
	)
	(symbol
		(lib_id "antmicroResistors0402:R_2k2_0402")
		(at 52.07 107.95 0)
		(unit 1)
		(exclude_from_sim no)
		(in_bom no)
		(on_board yes)
		(dnp yes)
		(property "Reference" "R216"
			(at 59.69 106.68 0)
			(effects
				(font
					(size 1.27 1.27)
				)
			)
		)
		(property "Value" "R_2k2_0402"
			(at 72.39 120.65 0)
			(effects
				(font
					(size 1.27 1.27)
					(thickness 0.15)
				)
				(justify left bottom)
				(hide yes)
			)
		)
		(property "Footprint" "antmicro-footprints:R_0402_1005Metric"
			(at 72.39 123.19 0)
			(effects
				(font
					(size 1.27 1.27)
					(thickness 0.15)
				)
				(justify left bottom)
				(hide yes)
			)
		)
		(property "Datasheet" "https://www.bourns.com/docs/product-datasheets/cr.pdf"
			(at 72.39 125.73 0)
			(effects
				(font
					(size 1.27 1.27)
					(thickness 0.15)
				)
				(justify left bottom)
				(hide yes)
			)
		)
		(property "Description" ""
			(at 52.07 107.95 0)
			(effects
				(font
					(size 1.27 1.27)
				)
			)
		)
		(property "Manufacturer" "Bourns"
			(at 72.39 130.81 0)
			(effects
				(font
					(size 1.27 1.27)
					(thickness 0.15)
				)
				(justify left bottom)
				(hide yes)
			)
		)
		(property "MPN" "CR0402-FX-2201GLF"
			(at 72.39 128.27 0)
			(effects
				(font
					(size 1.27 1.27)
					(thickness 0.15)
				)
				(justify left bottom)
				(hide yes)
			)
		)
		(property "Val" "2k2"
			(at 50.165 106.68 0)
			(effects
				(font
					(size 1.27 1.27)
					(thickness 0.15)
				)
			)
		)
		(property "DNP" "DNP"
			(at 54.61 107.95 0)
			(effects
				(font
					(size 1.27 1.27)
				)
			)
		)
		(property "License" "Apache-2.0"
			(at 72.39 133.35 0)
			(effects
				(font
					(size 1.27 1.27)
					(thickness 0.15)
				)
				(justify left bottom)
				(hide yes)
			)
		)
		(property "Author" "Antmicro"
			(at 72.39 135.89 0)
			(effects
				(font
					(size 1.27 1.27)
					(thickness 0.15)
				)
				(justify left bottom)
				(hide yes)
			)
		)
		(property "Tolerance" "1%"
			(at 72.39 118.11 0)
			(effects
				(font
					(size 1.27 1.27)
				)
				(justify left bottom)
				(hide yes)
			)
		)
		(pin "1"
		)
		(pin "2"
		)
		(instances
			(project "k410t-devboard"
				(path ""
					(reference "R216")
					(unit 1)
				)
			)
		)
	)
	(symbol
		(lib_id "antmicropower:GND")
		(at 309.88 214.63 0)
		(unit 1)
		(exclude_from_sim no)
		(in_bom yes)
		(on_board yes)
		(dnp no)
		(property "Reference" "#PWR0342"
			(at 309.88 220.98 0)
			(effects
				(font
					(size 1.27 1.27)
				)
				(hide yes)
			)
		)
		(property "Value" "GND"
			(at 309.88 218.44 0)
			(effects
				(font
					(size 1.27 1.27)
				)
			)
		)
		(property "Footprint" ""
			(at 318.77 222.25 0)
			(effects
				(font
					(size 1.27 1.27)
					(thickness 0.15)
				)
				(justify left bottom)
				(hide yes)
			)
		)
		(property "Datasheet" ""
			(at 318.77 227.33 0)
			(effects
				(font
					(size 1.27 1.27)
					(thickness 0.15)
				)
				(justify left bottom)
				(hide yes)
			)
		)
		(property "Description" ""
			(at 309.88 214.63 0)
			(effects
				(font
					(size 1.27 1.27)
				)
			)
		)
		(property "Author" "Antmicro"
			(at 318.77 222.25 0)
			(effects
				(font
					(size 1.27 1.27)
					(thickness 0.15)
				)
				(justify left bottom)
				(hide yes)
			)
		)
		(property "License" "Apache-2.0"
			(at 318.77 224.79 0)
			(effects
				(font
					(size 1.27 1.27)
					(thickness 0.15)
				)
				(justify left bottom)
				(hide yes)
			)
		)
		(pin "1"
		)
		(instances
			(project "k410t-devboard"
				(path ""
					(reference "#PWR0342")
					(unit 1)
				)
			)
		)
	)
	(symbol
		(lib_id "antmicroResistors0402:R_10k_0402")
		(at 52.07 240.03 0)
		(mirror x)
		(unit 1)
		(exclude_from_sim no)
		(in_bom no)
		(on_board yes)
		(dnp yes)
		(property "Reference" "R223"
			(at 59.69 238.76 0)
			(effects
				(font
					(size 1.27 1.27)
				)
			)
		)
		(property "Value" "R_10k_0402"
			(at 72.39 227.33 0)
			(effects
				(font
					(size 1.27 1.27)
					(thickness 0.15)
				)
				(justify left bottom)
				(hide yes)
			)
		)
		(property "Footprint" "antmicro-footprints:R_0402_1005Metric"
			(at 72.39 224.79 0)
			(effects
				(font
					(size 1.27 1.27)
					(thickness 0.15)
				)
				(justify left bottom)
				(hide yes)
			)
		)
		(property "Datasheet" "https://www.bourns.com/docs/product-datasheets/cr.pdf"
			(at 72.39 222.25 0)
			(effects
				(font
					(size 1.27 1.27)
					(thickness 0.15)
				)
				(justify left bottom)
				(hide yes)
			)
		)
		(property "Description" ""
			(at 52.07 240.03 0)
			(effects
				(font
					(size 1.27 1.27)
				)
			)
		)
		(property "Manufacturer" "Bourns"
			(at 72.39 217.17 0)
			(effects
				(font
					(size 1.27 1.27)
					(thickness 0.15)
				)
				(justify left bottom)
				(hide yes)
			)
		)
		(property "MPN" "CR0402-FX-1002GLF"
			(at 72.39 219.71 0)
			(effects
				(font
					(size 1.27 1.27)
					(thickness 0.15)
				)
				(justify left bottom)
				(hide yes)
			)
		)
		(property "Val" "10k"
			(at 50.165 238.76 0)
			(effects
				(font
					(size 1.27 1.27)
					(thickness 0.15)
				)
			)
		)
		(property "DNP" "DNP"
			(at 54.61 240.03 0)
			(effects
				(font
					(size 1.27 1.27)
				)
			)
		)
		(property "License" "Apache-2.0"
			(at 72.39 214.63 0)
			(effects
				(font
					(size 1.27 1.27)
					(thickness 0.15)
				)
				(justify left bottom)
				(hide yes)
			)
		)
		(property "Author" "Antmicro"
			(at 72.39 212.09 0)
			(effects
				(font
					(size 1.27 1.27)
					(thickness 0.15)
				)
				(justify left bottom)
				(hide yes)
			)
		)
		(property "Tolerance" "1%"
			(at 72.39 229.87 0)
			(effects
				(font
					(size 1.27 1.27)
				)
				(justify left bottom)
				(hide yes)
			)
		)
		(pin "1"
		)
		(pin "2"
		)
		(instances
			(project "k410t-devboard"
				(path ""
					(reference "R223")
					(unit 1)
				)
			)
		)
	)
)
